FILE_TYPE = MACRO_DRAWING;
SET COLOR_WIRE YELLOW;
SET COLOR_PROP MONO;
SET COLOR_DOT WHITE;
SET COLOR_ARC YELLOW;
SET COLOR_BODY GREEN;
SET COLOR_NOTE MONO;
SET PROP_DISPLAY VALUE;
SET PAGE_NUMBER P159;
FORCEADD OFFPAGE..3
R 2
(-650 4450);
FORCEPROP 2 LAST $XR0 144 
J 0
(-930 4450);
DISPLAY 0.638298 (-930 4450);
PAINT MONO (-930 4450);
FORCEPROP 2 LAST CDS_LIB mstr_standard
J 0
(-650 4450);
PAINT ORANGE (-650 4450);
DISPLAY INVISIBLE (-650 4450);
FORCEPROP 2 LAST PATH I111
J 0
(-925 4500);
DISPLAY 1.021277 (-925 4500);
PAINT ORANGE (-925 4500);
DISPLAY INVISIBLE (-925 4500);
FORCEPROP 1 LAST OFFPAGE TRUE
J 2
(-975 4325);
PAINT GREEN (-975 4325);
DISPLAY INVISIBLE (-975 4325);
FORCEPROP 1 LAST COMMENT_BODY TRUE
J 2
(-600 4350);
DISPLAY 1.170213 (-600 4350);
PAINT GREEN (-600 4350);
DISPLAY INVISIBLE (-600 4350);
FORCEADD OFFPAGE..4
R 2
(-650 4275);
FORCEPROP 2 LAST $XR0 144 
J 0
(-902 4275);
DISPLAY 0.638298 (-902 4275);
PAINT MONO (-902 4275);
FORCEPROP 2 LAST CDS_LIB mstr_standard
J 0
(-650 4275);
PAINT ORANGE (-650 4275);
DISPLAY INVISIBLE (-650 4275);
FORCEPROP 2 LAST PATH I112
J 0
(-900 4325);
DISPLAY 1.021277 (-900 4325);
PAINT ORANGE (-900 4325);
DISPLAY INVISIBLE (-900 4325);
FORCEPROP 1 LAST OFFPAGE TRUE
J 2
(-975 4150);
DISPLAY 0.872340 (-975 4150);
PAINT GREEN (-975 4150);
DISPLAY INVISIBLE (-975 4150);
FORCEPROP 1 LAST COMMENT_BODY TRUE
J 2
(-625 4175);
DISPLAY 0.872340 (-625 4175);
PAINT GREEN (-625 4175);
DISPLAY INVISIBLE (-625 4175);
FORCEADD OFFPAGE..4
R 2
(-625 3375);
FORCEPROP 2 LAST $XR0 144 
J 0
(-907 3375);
DISPLAY 0.638298 (-907 3375);
PAINT MONO (-907 3375);
FORCEPROP 2 LAST CDS_LIB mstr_standard
J 0
(-625 3375);
PAINT ORANGE (-625 3375);
DISPLAY INVISIBLE (-625 3375);
FORCEPROP 2 LAST PATH I113
J 0
(-875 3425);
DISPLAY 1.021277 (-875 3425);
PAINT ORANGE (-875 3425);
DISPLAY INVISIBLE (-875 3425);
FORCEPROP 1 LAST OFFPAGE TRUE
J 2
(-950 3250);
DISPLAY 0.872340 (-950 3250);
PAINT GREEN (-950 3250);
DISPLAY INVISIBLE (-950 3250);
FORCEPROP 1 LAST COMMENT_BODY TRUE
J 2
(-600 3275);
DISPLAY 0.872340 (-600 3275);
PAINT GREEN (-600 3275);
DISPLAY INVISIBLE (-600 3275);
FORCEADD OFFPAGE..3
R 2
(-600 3550);
FORCEPROP 2 LAST $XR0 144 
J 0
(-880 3550);
DISPLAY 0.638298 (-880 3550);
PAINT MONO (-880 3550);
FORCEPROP 2 LAST PATH I114
J 0
(-875 3600);
DISPLAY 1.021277 (-875 3600);
PAINT ORANGE (-875 3600);
DISPLAY INVISIBLE (-875 3600);
FORCEPROP 2 LAST CDS_LIB mstr_standard
J 0
(-600 3550);
PAINT ORANGE (-600 3550);
DISPLAY INVISIBLE (-600 3550);
FORCEPROP 1 LAST OFFPAGE TRUE
J 2
(-925 3425);
PAINT GREEN (-925 3425);
DISPLAY INVISIBLE (-925 3425);
FORCEPROP 1 LAST COMMENT_BODY TRUE
J 2
(-550 3450);
DISPLAY 1.170213 (-550 3450);
PAINT GREEN (-550 3450);
DISPLAY INVISIBLE (-550 3450);
FORCEADD OFFPAGE..3
R 2
(-575 1775);
FORCEPROP 2 LAST $XR0 144 
J 0
(-855 1775);
DISPLAY 0.638298 (-855 1775);
PAINT MONO (-855 1775);
FORCEPROP 2 LAST CDS_LIB mstr_standard
J 0
(-575 1775);
PAINT ORANGE (-575 1775);
DISPLAY INVISIBLE (-575 1775);
FORCEPROP 2 LAST PATH I117
J 0
(-850 1825);
DISPLAY 1.021277 (-850 1825);
PAINT ORANGE (-850 1825);
DISPLAY INVISIBLE (-850 1825);
FORCEPROP 1 LAST OFFPAGE TRUE
J 2
(-900 1650);
PAINT GREEN (-900 1650);
DISPLAY INVISIBLE (-900 1650);
FORCEPROP 1 LAST COMMENT_BODY TRUE
J 2
(-525 1675);
DISPLAY 1.170213 (-525 1675);
PAINT GREEN (-525 1675);
DISPLAY INVISIBLE (-525 1675);
FORCEADD OFFPAGE..4
R 2
(-600 1600);
FORCEPROP 2 LAST $XR0 144 
J 0
(-882 1600);
DISPLAY 0.638298 (-882 1600);
PAINT MONO (-882 1600);
FORCEPROP 2 LAST CDS_LIB mstr_standard
J 0
(-600 1600);
PAINT ORANGE (-600 1600);
DISPLAY INVISIBLE (-600 1600);
FORCEPROP 2 LAST PATH I118
J 0
(-850 1650);
DISPLAY 1.021277 (-850 1650);
PAINT ORANGE (-850 1650);
DISPLAY INVISIBLE (-850 1650);
FORCEPROP 1 LAST OFFPAGE TRUE
J 2
(-925 1475);
DISPLAY 0.872340 (-925 1475);
PAINT GREEN (-925 1475);
DISPLAY INVISIBLE (-925 1475);
FORCEPROP 1 LAST COMMENT_BODY TRUE
J 2
(-575 1500);
DISPLAY 0.872340 (-575 1500);
PAINT GREEN (-575 1500);
DISPLAY INVISIBLE (-575 1500);
FORCEADD OFFPAGE..3
(-2000 4950);
FORCEPROP 2 LAST $XR2 159 
J 0
(-1546 4950);
DISPLAY 0.638298 (-1546 4950);
PAINT MONO (-1546 4950);
FORCEPROP 2 LAST $XR1 156 
J 0
(-1666 4950);
DISPLAY 0.638298 (-1666 4950);
PAINT MONO (-1666 4950);
FORCEPROP 2 LAST $XR0 138 
J 0
(-1786 4950);
DISPLAY 0.638298 (-1786 4950);
PAINT MONO (-1786 4950);
FORCEPROP 2 LAST CDS_LIB mstr_standard
J 0
(-2000 4950);
PAINT ORANGE (-2000 4950);
DISPLAY INVISIBLE (-2000 4950);
FORCEPROP 2 LAST PATH I161
J 0
(-1525 5000);
DISPLAY 1.021277 (-1525 5000);
PAINT ORANGE (-1525 5000);
DISPLAY INVISIBLE (-1525 5000);
FORCEPROP 1 LAST OFFPAGE TRUE
J 0
(-1675 4825);
DISPLAY 0.872340 (-1675 4825);
PAINT GREEN (-1675 4825);
DISPLAY INVISIBLE (-1675 4825);
FORCEPROP 1 LAST COMMENT_BODY TRUE
J 0
(-2050 4850);
DISPLAY 0.872340 (-2050 4850);
PAINT GREEN (-2050 4850);
DISPLAY INVISIBLE (-2050 4850);
FORCEADD OFFPAGE..2
(-2000 4775);
FORCEPROP 2 LAST $XR2 159 
J 0
(-1571 4775);
DISPLAY 0.638298 (-1571 4775);
PAINT MONO (-1571 4775);
FORCEPROP 2 LAST $XR1 156 
J 0
(-1691 4775);
DISPLAY 0.638298 (-1691 4775);
PAINT MONO (-1691 4775);
FORCEPROP 2 LAST $XR0 138 
J 0
(-1811 4775);
DISPLAY 0.638298 (-1811 4775);
PAINT MONO (-1811 4775);
FORCEPROP 2 LAST CDS_LIB mstr_standard
J 0
(-2000 4775);
PAINT ORANGE (-2000 4775);
DISPLAY INVISIBLE (-2000 4775);
FORCEPROP 2 LAST PATH I162
J 0
(-1825 4850);
DISPLAY 1.021277 (-1825 4850);
PAINT ORANGE (-1825 4850);
DISPLAY INVISIBLE (-1825 4850);
FORCEPROP 1 LAST OFFPAGE TRUE
J 0
(-1675 4650);
DISPLAY 0.872340 (-1675 4650);
PAINT GREEN (-1675 4650);
DISPLAY INVISIBLE (-1675 4650);
FORCEPROP 1 LAST COMMENT_BODY TRUE
J 0
(-2045 4680);
DISPLAY 0.872340 (-2045 4680);
PAINT GREEN (-2045 4680);
DISPLAY INVISIBLE (-2045 4680);
FORCEADD OFFPAGE..3
(-2000 3775);
FORCEPROP 2 LAST $XR5 247 
J 0
(-1186 3775);
DISPLAY 0.638298 (-1186 3775);
PAINT MONO (-1186 3775);
FORCEPROP 2 LAST $XR4 156 
J 0
(-1306 3775);
DISPLAY 0.638298 (-1306 3775);
PAINT MONO (-1306 3775);
FORCEPROP 2 LAST $XR3 138 
J 0
(-1426 3775);
DISPLAY 0.638298 (-1426 3775);
PAINT MONO (-1426 3775);
FORCEPROP 2 LAST $XR2 111 
J 0
(-1546 3775);
DISPLAY 0.638298 (-1546 3775);
PAINT MONO (-1546 3775);
FORCEPROP 2 LAST $XR1 102 
J 0
(-1666 3775);
DISPLAY 0.638298 (-1666 3775);
PAINT MONO (-1666 3775);
FORCEPROP 2 LAST $XR0 101 
J 0
(-1786 3775);
DISPLAY 0.638298 (-1786 3775);
PAINT MONO (-1786 3775);
FORCEPROP 2 LAST PATH I168
J 0
(-1525 3825);
DISPLAY 1.021277 (-1525 3825);
PAINT ORANGE (-1525 3825);
DISPLAY INVISIBLE (-1525 3825);
FORCEPROP 2 LAST CDS_LIB mstr_standard
J 0
(-2000 3775);
PAINT ORANGE (-2000 3775);
DISPLAY INVISIBLE (-2000 3775);
FORCEPROP 1 LAST OFFPAGE TRUE
J 0
(-1675 3650);
DISPLAY 0.872340 (-1675 3650);
PAINT GREEN (-1675 3650);
DISPLAY INVISIBLE (-1675 3650);
FORCEPROP 1 LAST COMMENT_BODY TRUE
J 0
(-2050 3675);
DISPLAY 0.872340 (-2050 3675);
PAINT GREEN (-2050 3675);
DISPLAY INVISIBLE (-2050 3675);
FORCEADD OFFPAGE..2
(-2000 3600);
FORCEPROP 2 LAST $XR5 247 
J 0
(-1211 3600);
DISPLAY 0.638298 (-1211 3600);
PAINT MONO (-1211 3600);
FORCEPROP 2 LAST $XR4 156 
J 0
(-1331 3600);
DISPLAY 0.638298 (-1331 3600);
PAINT MONO (-1331 3600);
FORCEPROP 2 LAST $XR3 111 
J 0
(-1451 3600);
DISPLAY 0.638298 (-1451 3600);
PAINT MONO (-1451 3600);
FORCEPROP 2 LAST $XR2 102 
J 0
(-1571 3600);
DISPLAY 0.638298 (-1571 3600);
PAINT MONO (-1571 3600);
FORCEPROP 2 LAST $XR1 101 
J 0
(-1691 3600);
DISPLAY 0.638298 (-1691 3600);
PAINT MONO (-1691 3600);
FORCEPROP 2 LAST $XR0 138 
J 0
(-1811 3600);
DISPLAY 0.638298 (-1811 3600);
PAINT MONO (-1811 3600);
FORCEPROP 2 LAST PATH I169
J 0
(-1825 3675);
DISPLAY 1.021277 (-1825 3675);
PAINT ORANGE (-1825 3675);
DISPLAY INVISIBLE (-1825 3675);
FORCEPROP 2 LAST CDS_LIB mstr_standard
J 0
(-2000 3600);
PAINT ORANGE (-2000 3600);
DISPLAY INVISIBLE (-2000 3600);
FORCEPROP 1 LAST OFFPAGE TRUE
J 0
(-1675 3475);
DISPLAY 0.872340 (-1675 3475);
PAINT GREEN (-1675 3475);
DISPLAY INVISIBLE (-1675 3475);
FORCEPROP 1 LAST COMMENT_BODY TRUE
J 0
(-2045 3505);
DISPLAY 0.872340 (-2045 3505);
PAINT GREEN (-2045 3505);
DISPLAY INVISIBLE (-2045 3505);
FORCEADD OFFPAGE..3
(-1750 2525);
FORCEPROP 2 LAST $XR2 186 
J 0
(-1296 2525);
DISPLAY 0.638298 (-1296 2525);
PAINT MONO (-1296 2525);
FORCEPROP 2 LAST $XR1 185 
J 0
(-1416 2525);
DISPLAY 0.638298 (-1416 2525);
PAINT MONO (-1416 2525);
FORCEPROP 2 LAST $XR0 159 
J 0
(-1536 2525);
DISPLAY 0.638298 (-1536 2525);
PAINT MONO (-1536 2525);
FORCEPROP 2 LAST PATH I170
J 0
(-1275 2575);
DISPLAY 1.021277 (-1275 2575);
PAINT ORANGE (-1275 2575);
DISPLAY INVISIBLE (-1275 2575);
FORCEPROP 2 LAST CDS_LIB mstr_standard
J 0
(-1750 2525);
PAINT ORANGE (-1750 2525);
DISPLAY INVISIBLE (-1750 2525);
FORCEPROP 1 LAST OFFPAGE TRUE
J 0
(-1425 2400);
DISPLAY 0.872340 (-1425 2400);
PAINT GREEN (-1425 2400);
DISPLAY INVISIBLE (-1425 2400);
FORCEPROP 1 LAST COMMENT_BODY TRUE
J 0
(-1800 2425);
DISPLAY 0.872340 (-1800 2425);
PAINT GREEN (-1800 2425);
DISPLAY INVISIBLE (-1800 2425);
FORCEADD OFFPAGE..2
(-1750 2350);
FORCEPROP 2 LAST $XR2 186 
J 0
(-1321 2350);
DISPLAY 0.638298 (-1321 2350);
PAINT MONO (-1321 2350);
FORCEPROP 2 LAST $XR1 185 
J 0
(-1441 2350);
DISPLAY 0.638298 (-1441 2350);
PAINT MONO (-1441 2350);
FORCEPROP 2 LAST $XR0 159 
J 0
(-1561 2350);
DISPLAY 0.638298 (-1561 2350);
PAINT MONO (-1561 2350);
FORCEPROP 2 LAST PATH I171
J 0
(-1300 2400);
DISPLAY 1.021277 (-1300 2400);
PAINT ORANGE (-1300 2400);
DISPLAY INVISIBLE (-1300 2400);
FORCEPROP 2 LAST CDS_LIB mstr_standard
J 0
(-1750 2350);
PAINT ORANGE (-1750 2350);
DISPLAY INVISIBLE (-1750 2350);
FORCEPROP 1 LAST OFFPAGE TRUE
J 0
(-1425 2225);
DISPLAY 0.872340 (-1425 2225);
PAINT GREEN (-1425 2225);
DISPLAY INVISIBLE (-1425 2225);
FORCEPROP 1 LAST COMMENT_BODY TRUE
J 0
(-1795 2255);
DISPLAY 0.872340 (-1795 2255);
PAINT GREEN (-1795 2255);
DISPLAY INVISIBLE (-1795 2255);
FORCEADD OFFPAGE..3
R 2
(-4450 4950);
FORCEPROP 2 LAST $XR0 144 
J 0
(-4730 4950);
DISPLAY 0.638298 (-4730 4950);
PAINT MONO (-4730 4950);
FORCEPROP 2 LAST PATH I185
J 0
(-4725 5000);
DISPLAY 1.021277 (-4725 5000);
PAINT ORANGE (-4725 5000);
DISPLAY INVISIBLE (-4725 5000);
FORCEPROP 2 LAST CDS_LIB mstr_standard
J 0
(-4450 4950);
PAINT ORANGE (-4450 4950);
DISPLAY INVISIBLE (-4450 4950);
FORCEPROP 1 LAST OFFPAGE TRUE
J 2
(-4775 4825);
PAINT GREEN (-4775 4825);
DISPLAY INVISIBLE (-4775 4825);
FORCEPROP 1 LAST COMMENT_BODY TRUE
J 2
(-4400 4850);
DISPLAY 1.170213 (-4400 4850);
PAINT GREEN (-4400 4850);
DISPLAY INVISIBLE (-4400 4850);
FORCEADD OFFPAGE..4
R 2
(-4450 4775);
FORCEPROP 2 LAST $XR0 144 
J 0
(-4702 4775);
DISPLAY 0.638298 (-4702 4775);
PAINT MONO (-4702 4775);
FORCEPROP 2 LAST CDS_LIB mstr_standard
J 0
(-4450 4775);
PAINT ORANGE (-4450 4775);
DISPLAY INVISIBLE (-4450 4775);
FORCEPROP 2 LAST PATH I186
J 0
(-4400 4850);
DISPLAY 1.021277 (-4400 4850);
PAINT ORANGE (-4400 4850);
DISPLAY INVISIBLE (-4400 4850);
FORCEPROP 1 LAST OFFPAGE TRUE
J 2
(-4775 4650);
DISPLAY 0.872340 (-4775 4650);
PAINT GREEN (-4775 4650);
DISPLAY INVISIBLE (-4775 4650);
FORCEPROP 1 LAST COMMENT_BODY TRUE
J 2
(-4425 4675);
DISPLAY 0.872340 (-4425 4675);
PAINT GREEN (-4425 4675);
DISPLAY INVISIBLE (-4425 4675);
FORCEADD OFFPAGE..3
R 2
(-4450 3775);
FORCEPROP 2 LAST $XR0 144 
J 0
(-4730 3775);
DISPLAY 0.638298 (-4730 3775);
PAINT MONO (-4730 3775);
FORCEPROP 2 LAST CDS_LIB mstr_standard
J 0
(-4450 3775);
PAINT ORANGE (-4450 3775);
DISPLAY INVISIBLE (-4450 3775);
FORCEPROP 2 LAST PATH I187
J 0
(-4725 3825);
DISPLAY 1.021277 (-4725 3825);
PAINT ORANGE (-4725 3825);
DISPLAY INVISIBLE (-4725 3825);
FORCEPROP 1 LAST OFFPAGE TRUE
J 2
(-4775 3650);
PAINT GREEN (-4775 3650);
DISPLAY INVISIBLE (-4775 3650);
FORCEPROP 1 LAST COMMENT_BODY TRUE
J 2
(-4400 3675);
DISPLAY 1.170213 (-4400 3675);
PAINT GREEN (-4400 3675);
DISPLAY INVISIBLE (-4400 3675);
FORCEADD OFFPAGE..4
R 2
(-4450 3600);
FORCEPROP 2 LAST $XR0 144 
J 0
(-4702 3600);
DISPLAY 0.638298 (-4702 3600);
PAINT MONO (-4702 3600);
FORCEPROP 2 LAST PATH I188
J 0
(-4400 3675);
DISPLAY 1.021277 (-4400 3675);
PAINT ORANGE (-4400 3675);
DISPLAY INVISIBLE (-4400 3675);
FORCEPROP 2 LAST CDS_LIB mstr_standard
J 0
(-4450 3600);
PAINT ORANGE (-4450 3600);
DISPLAY INVISIBLE (-4450 3600);
FORCEPROP 1 LAST OFFPAGE TRUE
J 2
(-4775 3475);
DISPLAY 0.872340 (-4775 3475);
PAINT GREEN (-4775 3475);
DISPLAY INVISIBLE (-4775 3475);
FORCEPROP 1 LAST COMMENT_BODY TRUE
J 2
(-4425 3500);
DISPLAY 0.872340 (-4425 3500);
PAINT GREEN (-4425 3500);
DISPLAY INVISIBLE (-4425 3500);
FORCEADD OFFPAGE..3
R 2
(-4400 2525);
FORCEPROP 2 LAST $XR0 144 
J 0
(-4680 2525);
DISPLAY 0.638298 (-4680 2525);
PAINT MONO (-4680 2525);
FORCEPROP 2 LAST CDS_LIB mstr_standard
J 0
(-4400 2525);
PAINT ORANGE (-4400 2525);
DISPLAY INVISIBLE (-4400 2525);
FORCEPROP 2 LAST PATH I189
J 0
(-4675 2575);
DISPLAY 1.021277 (-4675 2575);
PAINT ORANGE (-4675 2575);
DISPLAY INVISIBLE (-4675 2575);
FORCEPROP 1 LAST OFFPAGE TRUE
J 2
(-4725 2400);
PAINT GREEN (-4725 2400);
DISPLAY INVISIBLE (-4725 2400);
FORCEPROP 1 LAST COMMENT_BODY TRUE
J 2
(-4350 2425);
DISPLAY 1.170213 (-4350 2425);
PAINT GREEN (-4350 2425);
DISPLAY INVISIBLE (-4350 2425);
FORCEADD OFFPAGE..4
R 2
(-4400 2350);
FORCEPROP 2 LAST $XR0 144 
J 0
(-4682 2350);
DISPLAY 0.638298 (-4682 2350);
PAINT MONO (-4682 2350);
FORCEPROP 2 LAST CDS_LIB mstr_standard
J 0
(-4400 2350);
PAINT ORANGE (-4400 2350);
DISPLAY INVISIBLE (-4400 2350);
FORCEPROP 2 LAST PATH I190
J 0
(-4650 2400);
DISPLAY 1.021277 (-4650 2400);
PAINT ORANGE (-4650 2400);
DISPLAY INVISIBLE (-4650 2400);
FORCEPROP 1 LAST OFFPAGE TRUE
J 2
(-4725 2225);
DISPLAY 0.872340 (-4725 2225);
PAINT GREEN (-4725 2225);
DISPLAY INVISIBLE (-4725 2225);
FORCEPROP 1 LAST COMMENT_BODY TRUE
J 2
(-4375 2250);
DISPLAY 0.872340 (-4375 2250);
PAINT GREEN (-4375 2250);
DISPLAY INVISIBLE (-4375 2250);
FORCEADD OFFPAGE..6
(-4625 1450);
FORCEPROP 2 LAST $XR2 159 
J 0
(-5145 1450);
DISPLAY 0.638298 (-5145 1450);
PAINT MONO (-5145 1450);
FORCEPROP 2 LAST $XR1 156 
J 0
(-5025 1450);
DISPLAY 0.638298 (-5025 1450);
PAINT MONO (-5025 1450);
FORCEPROP 2 LAST $XR0 138 
J 0
(-4905 1450);
DISPLAY 0.638298 (-4905 1450);
PAINT MONO (-4905 1450);
FORCEPROP 2 LAST PATH I195
J 0
(-4575 1525);
DISPLAY 1.021277 (-4575 1525);
PAINT ORANGE (-4575 1525);
DISPLAY INVISIBLE (-4575 1525);
FORCEPROP 2 LAST CDS_LIB mstr_standard
J 0
(-4625 1450);
PAINT MONO (-4625 1450);
DISPLAY INVISIBLE (-4625 1450);
FORCEPROP 1 LAST OFFPAGE TRUE
J 0
(-4300 1325);
DISPLAY 0.872340 (-4300 1325);
PAINT GREEN (-4300 1325);
DISPLAY INVISIBLE (-4300 1325);
FORCEPROP 1 LAST COMMENT_BODY TRUE
J 0
(-4525 1375);
DISPLAY 0.872340 (-4525 1375);
PAINT GREEN (-4525 1375);
DISPLAY INVISIBLE (-4525 1375);
FORCEADD OFFPAGE..1
(-4625 1325);
FORCEPROP 2 LAST $XR2 156 
J 0
(-5147 1325);
DISPLAY 0.638298 (-5147 1325);
PAINT MONO (-5147 1325);
FORCEPROP 2 LAST $XR1 159 
J 0
(-5027 1325);
DISPLAY 0.638298 (-5027 1325);
PAINT MONO (-5027 1325);
FORCEPROP 2 LAST $XR0 138 
J 0
(-4907 1325);
DISPLAY 0.638298 (-4907 1325);
PAINT MONO (-4907 1325);
FORCEPROP 2 LAST PATH I196
J 0
(-4575 1400);
DISPLAY 1.021277 (-4575 1400);
PAINT ORANGE (-4575 1400);
DISPLAY INVISIBLE (-4575 1400);
FORCEPROP 2 LAST CDS_LIB mstr_standard
J 0
(-4625 1325);
PAINT MONO (-4625 1325);
DISPLAY INVISIBLE (-4625 1325);
FORCEPROP 1 LAST OFFPAGE TRUE
J 0
(-4300 1200);
DISPLAY 0.872340 (-4300 1200);
PAINT GREEN (-4300 1200);
DISPLAY INVISIBLE (-4300 1200);
FORCEPROP 1 LAST COMMENT_BODY TRUE
J 0
(-4500 1225);
DISPLAY 0.872340 (-4500 1225);
PAINT GREEN (-4500 1225);
DISPLAY INVISIBLE (-4500 1225);
FORCEADD OFFPAGE..6
(-4625 1575);
FORCEPROP 2 LAST $XR2 186 
J 0
(-5145 1575);
DISPLAY 0.638298 (-5145 1575);
PAINT MONO (-5145 1575);
FORCEPROP 2 LAST $XR1 185 
J 0
(-5025 1575);
DISPLAY 0.638298 (-5025 1575);
PAINT MONO (-5025 1575);
FORCEPROP 2 LAST $XR0 159 
J 0
(-4905 1575);
DISPLAY 0.638298 (-4905 1575);
PAINT MONO (-4905 1575);
FORCEPROP 2 LAST PATH I197
J 0
(-4575 1650);
DISPLAY 1.021277 (-4575 1650);
PAINT ORANGE (-4575 1650);
DISPLAY INVISIBLE (-4575 1650);
FORCEPROP 2 LAST CDS_LIB mstr_standard
J 0
(-4625 1575);
PAINT MONO (-4625 1575);
DISPLAY INVISIBLE (-4625 1575);
FORCEPROP 1 LAST OFFPAGE TRUE
J 0
(-4300 1450);
DISPLAY 0.872340 (-4300 1450);
PAINT GREEN (-4300 1450);
DISPLAY INVISIBLE (-4300 1450);
FORCEPROP 1 LAST COMMENT_BODY TRUE
J 0
(-4525 1500);
DISPLAY 0.872340 (-4525 1500);
PAINT GREEN (-4525 1500);
DISPLAY INVISIBLE (-4525 1500);
FORCEADD OFFPAGE..1
(-4625 1200);
FORCEPROP 2 LAST $XR2 186 
J 0
(-5147 1200);
DISPLAY 0.638298 (-5147 1200);
PAINT MONO (-5147 1200);
FORCEPROP 2 LAST $XR1 185 
J 0
(-5027 1200);
DISPLAY 0.638298 (-5027 1200);
PAINT MONO (-5027 1200);
FORCEPROP 2 LAST $XR0 159 
J 0
(-4907 1200);
DISPLAY 0.638298 (-4907 1200);
PAINT MONO (-4907 1200);
FORCEPROP 2 LAST PATH I198
J 0
(-4575 1275);
DISPLAY 1.021277 (-4575 1275);
PAINT ORANGE (-4575 1275);
DISPLAY INVISIBLE (-4575 1275);
FORCEPROP 2 LAST CDS_LIB mstr_standard
J 0
(-4625 1200);
PAINT MONO (-4625 1200);
DISPLAY INVISIBLE (-4625 1200);
FORCEPROP 1 LAST OFFPAGE TRUE
J 0
(-4300 1075);
DISPLAY 0.872340 (-4300 1075);
PAINT GREEN (-4300 1075);
DISPLAY INVISIBLE (-4300 1075);
FORCEPROP 1 LAST COMMENT_BODY TRUE
J 0
(-4500 1100);
DISPLAY 0.872340 (-4500 1100);
PAINT GREEN (-4500 1100);
DISPLAY INVISIBLE (-4500 1100);
FORCEADD OFFPAGE..3
(-2075 1450);
FORCEPROP 2 LAST $XR0 139 
J 0
(-1861 1450);
DISPLAY 0.638298 (-1861 1450);
PAINT MONO (-1861 1450);
FORCEPROP 2 LAST CDS_LIB mstr_standard
J 0
(-2075 1450);
PAINT MONO (-2075 1450);
DISPLAY INVISIBLE (-2075 1450);
FORCEPROP 2 LAST PATH I199
J 0
(-2025 1525);
DISPLAY 1.021277 (-2025 1525);
PAINT ORANGE (-2025 1525);
DISPLAY INVISIBLE (-2025 1525);
FORCEPROP 1 LAST OFFPAGE TRUE
J 0
(-1750 1325);
DISPLAY 0.872340 (-1750 1325);
PAINT GREEN (-1750 1325);
DISPLAY INVISIBLE (-1750 1325);
FORCEPROP 1 LAST COMMENT_BODY TRUE
J 0
(-2125 1350);
DISPLAY 0.872340 (-2125 1350);
PAINT GREEN (-2125 1350);
DISPLAY INVISIBLE (-2125 1350);
FORCEADD OFFPAGE..2
(-2075 1325);
FORCEPROP 2 LAST $XR0 139 
J 0
(-1886 1325);
DISPLAY 0.638298 (-1886 1325);
PAINT MONO (-1886 1325);
FORCEPROP 2 LAST CDS_LIB mstr_standard
J 0
(-2075 1325);
PAINT MONO (-2075 1325);
DISPLAY INVISIBLE (-2075 1325);
FORCEPROP 2 LAST PATH I200
J 0
(-1900 1400);
DISPLAY 1.021277 (-1900 1400);
PAINT ORANGE (-1900 1400);
DISPLAY INVISIBLE (-1900 1400);
FORCEPROP 1 LAST OFFPAGE TRUE
J 0
(-1750 1200);
DISPLAY 0.872340 (-1750 1200);
PAINT GREEN (-1750 1200);
DISPLAY INVISIBLE (-1750 1200);
FORCEPROP 1 LAST COMMENT_BODY TRUE
J 0
(-2120 1230);
DISPLAY 0.872340 (-2120 1230);
PAINT GREEN (-2120 1230);
DISPLAY INVISIBLE (-2120 1230);
FORCEADD P3V3_STBY..1
(-3375 3200);
FORCEPROP 3 LASTPIN (-3375 3150) SIG_NAME P3V3_STBY\g
J 0
(-3365 3160);
DISPLAY 0.659574 (-3365 3160);
PAINT MONO (-3365 3160);
DISPLAY INVISIBLE (-3365 3160);
FORCEPROP 1 LAST PATH I209
J 0
(-3330 3202);
DISPLAY 0.340426 (-3330 3202);
PAINT GREEN (-3330 3202);
DISPLAY INVISIBLE (-3330 3202);
FORCEPROP 2 LAST CDS_LIB mstr_symbols
J 0
(-3375 3200);
PAINT MONO (-3375 3200);
DISPLAY INVISIBLE (-3375 3200);
FORCEPROP 1 LAST SIZE 1B
J 0
(-3330 3222);
DISPLAY 0.340426 (-3330 3222);
PAINT GREEN (-3330 3222);
DISPLAY INVISIBLE (-3330 3222);
FORCEPROP 1 LAST VOLTAGE 3.3V
J 0
(-3420 3157);
DISPLAY 0.340426 (-3420 3157);
PAINT SKYBLUE (-3420 3157);
DISPLAY INVISIBLE (-3420 3157);
FORCEPROP 1 LAST BODY_TYPE PLUMBING
J 0
(-3420 3157);
DISPLAY 0.340426 (-3420 3157);
PAINT GREEN (-3420 3157);
DISPLAY INVISIBLE (-3420 3157);
FORCEPROP 1 LAST HDL_POWER P3V3_STBY
J 0
(-3675 3075);
DISPLAY 0.872340 (-3675 3075);
PAINT ORANGE (-3675 3075);
DISPLAY INVISIBLE (-3675 3075);
FORCEADD RES..2
(-3375 2900);
FORCEPROP 1 LAST MATERIAL EMPTY
J 0
(-3335 2825);
DISPLAY 0.617021 (-3335 2825);
PAINT RED (-3335 2825);
FORCEPROP 1 LAST PART_NUMBER G21796-311
J 0
(-3335 2775);
DISPLAY 0.617021 (-3335 2775);
PAINT BLUE (-3335 2775);
FORCEPROP 1 LASTPIN (-3375 2800) $PN 2
J 0
(-3370 2810);
DISPLAY 0.787234 (-3370 2810);
PAINT ORANGE (-3370 2810);
FORCEPROP 1 LASTPIN (-3375 3000) $PN 1
J 0
(-3370 2962);
DISPLAY 0.787234 (-3370 2962);
PAINT ORANGE (-3370 2962);
FORCEPROP 1 LAST PACK_TYPE 0402
J 0
(-3335 2725);
DISPLAY 0.617021 (-3335 2725);
PAINT SKYBLUE (-3335 2725);
FORCEPROP 1 LAST TOLERANCE 1.0%
J 0
(-3330 2925);
DISPLAY 0.617021 (-3330 2925);
PAINT SKYBLUE (-3330 2925);
FORCEPROP 1 LAST WATTAGE 1/16W
J 0
(-3335 2875);
DISPLAY 0.617021 (-3335 2875);
PAINT SKYBLUE (-3335 2875);
FORCEPROP 1 LAST VALUE 2.26K
J 0
(-3330 2975);
DISPLAY 0.617021 (-3330 2975);
PAINT SKYBLUE (-3330 2975);
FORCEPROP 1 LAST LOCATION R8G3
J 0
(-3330 3025);
DISPLAY 0.617021 (-3330 3025);
PAINT AQUA (-3330 3025);
FORCEPROP 2 LAST SEC_TYPE 0402
J 0
(-3325 3125);
DISPLAY 1.021277 (-3325 3125);
PAINT ORANGE (-3325 3125);
DISPLAY INVISIBLE (-3325 3125);
FORCEPROP 2 LAST SEC 1
J 0
(-3325 3125);
PAINT MONO (-3325 3125);
DISPLAY INVISIBLE (-3325 3125);
FORCEPROP 1 LAST PATH I210
J 0
(-3325 3075);
DISPLAY 0.978723 (-3325 3075);
PAINT WHITE (-3325 3075);
DISPLAY INVISIBLE (-3325 3075);
FORCEPROP 0 LAST BOM_COST SM_CONTROLLER
J 0
(-3325 3225);
DISPLAY 1.021277 (-3325 3225);
PAINT ORANGE (-3325 3225);
DISPLAY INVISIBLE (-3325 3225);
FORCEPROP 0 LAST SKU B
J 0
(-3325 3125);
DISPLAY 1.021277 (-3325 3125);
PAINT ORANGE (-3325 3125);
DISPLAY INVISIBLE (-3325 3125);
FORCEPROP 0 LAST ROOM SMBUS
J 0
(-3325 3125);
DISPLAY 1.021277 (-3325 3125);
PAINT ORANGE (-3325 3125);
DISPLAY INVISIBLE (-3325 3125);
FORCEPROP 2 LAST CDS_LOCATION R8G3
J 0
(-3330 3025);
DISPLAY 0.617021 (-3330 3025);
PAINT AQUA (-3330 3025);
DISPLAY INVISIBLE (-3330 3025);
FORCEPROP 2 LAST CDS_LIB mstr_discrete
J 0
(-3375 2900);
PAINT ORANGE (-3375 2900);
DISPLAY INVISIBLE (-3375 2900);
FORCEADD P3V3_STBY..1
(-3725 3200);
FORCEPROP 3 LASTPIN (-3725 3150) SIG_NAME P3V3_STBY\g
J 0
(-3715 3160);
DISPLAY 0.659574 (-3715 3160);
PAINT MONO (-3715 3160);
DISPLAY INVISIBLE (-3715 3160);
FORCEPROP 1 LAST SIZE 1B
J 0
(-3680 3222);
DISPLAY 0.340426 (-3680 3222);
PAINT GREEN (-3680 3222);
DISPLAY INVISIBLE (-3680 3222);
FORCEPROP 1 LAST PATH I211
J 0
(-3680 3202);
DISPLAY 0.340426 (-3680 3202);
PAINT GREEN (-3680 3202);
DISPLAY INVISIBLE (-3680 3202);
FORCEPROP 2 LAST CDS_LIB mstr_symbols
J 0
(-3725 3200);
PAINT MONO (-3725 3200);
DISPLAY INVISIBLE (-3725 3200);
FORCEPROP 1 LAST VOLTAGE 3.3V
J 0
(-3770 3157);
DISPLAY 0.340426 (-3770 3157);
PAINT SKYBLUE (-3770 3157);
DISPLAY INVISIBLE (-3770 3157);
FORCEPROP 1 LAST BODY_TYPE PLUMBING
J 0
(-3770 3157);
DISPLAY 0.340426 (-3770 3157);
PAINT GREEN (-3770 3157);
DISPLAY INVISIBLE (-3770 3157);
FORCEPROP 1 LAST HDL_POWER P3V3_STBY
J 0
(-4025 3075);
DISPLAY 0.872340 (-4025 3075);
PAINT ORANGE (-4025 3075);
DISPLAY INVISIBLE (-4025 3075);
FORCEADD RES..2
(-3725 2900);
FORCEPROP 1 LASTPIN (-3725 2800) $PN 2
J 0
(-3720 2810);
DISPLAY 0.787234 (-3720 2810);
PAINT ORANGE (-3720 2810);
FORCEPROP 1 LASTPIN (-3725 3000) $PN 1
J 0
(-3720 2962);
DISPLAY 0.787234 (-3720 2962);
PAINT ORANGE (-3720 2962);
FORCEPROP 1 LAST PACK_TYPE 0402
J 0
(-3685 2725);
DISPLAY 0.617021 (-3685 2725);
PAINT SKYBLUE (-3685 2725);
FORCEPROP 1 LAST WATTAGE 1/16W
J 0
(-3685 2875);
DISPLAY 0.617021 (-3685 2875);
PAINT SKYBLUE (-3685 2875);
FORCEPROP 1 LAST MATERIAL EMPTY
J 0
(-3685 2825);
DISPLAY 0.617021 (-3685 2825);
PAINT RED (-3685 2825);
FORCEPROP 1 LAST PART_NUMBER G21796-311
J 0
(-3685 2775);
DISPLAY 0.617021 (-3685 2775);
PAINT BLUE (-3685 2775);
FORCEPROP 1 LAST TOLERANCE 1.0%
J 0
(-3680 2925);
DISPLAY 0.617021 (-3680 2925);
PAINT SKYBLUE (-3680 2925);
FORCEPROP 1 LAST VALUE 2.26K
J 0
(-3680 2975);
DISPLAY 0.617021 (-3680 2975);
PAINT SKYBLUE (-3680 2975);
FORCEPROP 1 LAST LOCATION R8G6
J 0
(-3680 3025);
DISPLAY 0.617021 (-3680 3025);
PAINT AQUA (-3680 3025);
FORCEPROP 2 LAST SEC_TYPE 0402
J 0
(-3675 3125);
DISPLAY 1.021277 (-3675 3125);
PAINT ORANGE (-3675 3125);
DISPLAY INVISIBLE (-3675 3125);
FORCEPROP 2 LAST SEC 1
J 0
(-3675 3125);
PAINT MONO (-3675 3125);
DISPLAY INVISIBLE (-3675 3125);
FORCEPROP 0 LAST SKU B
J 0
(-3675 3125);
DISPLAY 1.021277 (-3675 3125);
PAINT ORANGE (-3675 3125);
DISPLAY INVISIBLE (-3675 3125);
FORCEPROP 0 LAST BOM_COST SM_CONTROLLER
J 0
(-3675 3225);
DISPLAY 1.021277 (-3675 3225);
PAINT ORANGE (-3675 3225);
DISPLAY INVISIBLE (-3675 3225);
FORCEPROP 1 LAST PATH I212
J 0
(-3675 3075);
DISPLAY 0.978723 (-3675 3075);
PAINT WHITE (-3675 3075);
DISPLAY INVISIBLE (-3675 3075);
FORCEPROP 0 LAST ROOM SMBUS
J 0
(-3675 3125);
DISPLAY 1.021277 (-3675 3125);
PAINT ORANGE (-3675 3125);
DISPLAY INVISIBLE (-3675 3125);
FORCEPROP 2 LAST CDS_LOCATION R8G6
J 0
(-3680 3025);
DISPLAY 0.617021 (-3680 3025);
PAINT AQUA (-3680 3025);
DISPLAY INVISIBLE (-3680 3025);
FORCEPROP 2 LAST CDS_LIB mstr_discrete
J 0
(-3725 2900);
PAINT ORANGE (-3725 2900);
DISPLAY INVISIBLE (-3725 2900);
FORCEADD P3V3_STBY..1
(550 5125);
FORCEPROP 3 LASTPIN (550 5075) SIG_NAME P3V3_STBY\g
J 0
(560 5085);
DISPLAY 0.659574 (560 5085);
PAINT MONO (560 5085);
DISPLAY INVISIBLE (560 5085);
FORCEPROP 2 LAST CDS_LIB mstr_symbols
J 0
(550 5125);
PAINT MONO (550 5125);
DISPLAY INVISIBLE (550 5125);
FORCEPROP 1 LAST SIZE 1B
J 0
(595 5147);
DISPLAY 0.340426 (595 5147);
PAINT GREEN (595 5147);
DISPLAY INVISIBLE (595 5147);
FORCEPROP 1 LAST PATH I213
J 0
(595 5127);
DISPLAY 0.340426 (595 5127);
PAINT GREEN (595 5127);
DISPLAY INVISIBLE (595 5127);
FORCEPROP 1 LAST VOLTAGE 3.3V
J 0
(505 5082);
DISPLAY 0.340426 (505 5082);
PAINT SKYBLUE (505 5082);
DISPLAY INVISIBLE (505 5082);
FORCEPROP 1 LAST BODY_TYPE PLUMBING
J 0
(505 5082);
DISPLAY 0.340426 (505 5082);
PAINT GREEN (505 5082);
DISPLAY INVISIBLE (505 5082);
FORCEPROP 1 LAST HDL_POWER P3V3_STBY
J 0
(250 5000);
DISPLAY 0.872340 (250 5000);
PAINT ORANGE (250 5000);
DISPLAY INVISIBLE (250 5000);
FORCEADD RES..2
(550 4825);
FORCEPROP 1 LAST PART_NUMBER G21796-311
J 0
(590 4700);
DISPLAY 0.617021 (590 4700);
PAINT BLUE (590 4700);
FORCEPROP 1 LAST MATERIAL CHIP
J 0
(590 4750);
DISPLAY 0.617021 (590 4750);
PAINT SKYBLUE (590 4750);
FORCEPROP 1 LAST WATTAGE 1/16W
J 0
(590 4800);
DISPLAY 0.617021 (590 4800);
PAINT SKYBLUE (590 4800);
FORCEPROP 1 LAST TOLERANCE 1.0%
J 0
(595 4850);
DISPLAY 0.617021 (595 4850);
PAINT SKYBLUE (595 4850);
FORCEPROP 1 LAST VALUE 2.26K
J 0
(595 4900);
DISPLAY 0.617021 (595 4900);
PAINT SKYBLUE (595 4900);
FORCEPROP 1 LAST LOCATION R2U5
J 0
(595 4950);
DISPLAY 0.617021 (595 4950);
PAINT AQUA (595 4950);
FORCEPROP 1 LAST PACK_TYPE 0402
J 0
(590 4650);
DISPLAY 0.617021 (590 4650);
PAINT SKYBLUE (590 4650);
FORCEPROP 1 LASTPIN (550 4725) $PN 2
J 0
(555 4735);
DISPLAY 0.787234 (555 4735);
PAINT ORANGE (555 4735);
FORCEPROP 1 LASTPIN (550 4925) $PN 1
J 0
(555 4887);
DISPLAY 0.787234 (555 4887);
PAINT ORANGE (555 4887);
FORCEPROP 2 LAST SEC_TYPE 0402
J 0
(600 5050);
DISPLAY 1.021277 (600 5050);
PAINT ORANGE (600 5050);
DISPLAY INVISIBLE (600 5050);
FORCEPROP 2 LAST SEC 1
J 0
(600 5050);
PAINT MONO (600 5050);
DISPLAY INVISIBLE (600 5050);
FORCEPROP 0 LAST BOM_COST SM_CONTROLLER
J 0
(600 5150);
DISPLAY 1.021277 (600 5150);
PAINT ORANGE (600 5150);
DISPLAY INVISIBLE (600 5150);
FORCEPROP 1 LAST PATH I214
J 0
(600 5000);
DISPLAY 0.978723 (600 5000);
PAINT WHITE (600 5000);
DISPLAY INVISIBLE (600 5000);
FORCEPROP 0 LAST SKU B
J 0
(600 5050);
DISPLAY 1.021277 (600 5050);
PAINT ORANGE (600 5050);
DISPLAY INVISIBLE (600 5050);
FORCEPROP 0 LAST ROOM SMBUS
J 0
(600 5050);
DISPLAY 1.021277 (600 5050);
PAINT ORANGE (600 5050);
DISPLAY INVISIBLE (600 5050);
FORCEPROP 2 LAST CDS_LOCATION R2U5
J 0
(595 4950);
DISPLAY 0.617021 (595 4950);
PAINT AQUA (595 4950);
DISPLAY INVISIBLE (595 4950);
FORCEPROP 2 LAST CDS_LIB mstr_discrete
J 0
(550 4825);
PAINT ORANGE (550 4825);
DISPLAY INVISIBLE (550 4825);
FORCEADD P3V3_STBY..1
(200 5125);
FORCEPROP 3 LASTPIN (200 5075) SIG_NAME P3V3_STBY\g
J 0
(210 5085);
DISPLAY 0.659574 (210 5085);
PAINT MONO (210 5085);
DISPLAY INVISIBLE (210 5085);
FORCEPROP 1 LAST SIZE 1B
J 0
(245 5147);
DISPLAY 0.340426 (245 5147);
PAINT GREEN (245 5147);
DISPLAY INVISIBLE (245 5147);
FORCEPROP 2 LAST CDS_LIB mstr_symbols
J 0
(200 5125);
PAINT MONO (200 5125);
DISPLAY INVISIBLE (200 5125);
FORCEPROP 1 LAST PATH I215
J 0
(245 5127);
DISPLAY 0.340426 (245 5127);
PAINT GREEN (245 5127);
DISPLAY INVISIBLE (245 5127);
FORCEPROP 1 LAST VOLTAGE 3.3V
J 0
(155 5082);
DISPLAY 0.340426 (155 5082);
PAINT SKYBLUE (155 5082);
DISPLAY INVISIBLE (155 5082);
FORCEPROP 1 LAST BODY_TYPE PLUMBING
J 0
(155 5082);
DISPLAY 0.340426 (155 5082);
PAINT GREEN (155 5082);
DISPLAY INVISIBLE (155 5082);
FORCEPROP 1 LAST HDL_POWER P3V3_STBY
J 0
(-100 5000);
DISPLAY 0.872340 (-100 5000);
PAINT ORANGE (-100 5000);
DISPLAY INVISIBLE (-100 5000);
FORCEADD RES..2
(200 4825);
FORCEPROP 1 LAST PART_NUMBER G21796-311
J 0
(240 4700);
DISPLAY 0.617021 (240 4700);
PAINT BLUE (240 4700);
FORCEPROP 1 LAST PACK_TYPE 0402
J 0
(240 4650);
DISPLAY 0.617021 (240 4650);
PAINT SKYBLUE (240 4650);
FORCEPROP 1 LAST MATERIAL CHIP
J 0
(240 4750);
DISPLAY 0.617021 (240 4750);
PAINT SKYBLUE (240 4750);
FORCEPROP 1 LAST WATTAGE 1/16W
J 0
(240 4800);
DISPLAY 0.617021 (240 4800);
PAINT SKYBLUE (240 4800);
FORCEPROP 1 LAST TOLERANCE 1.0%
J 0
(245 4850);
DISPLAY 0.617021 (245 4850);
PAINT SKYBLUE (245 4850);
FORCEPROP 1 LAST VALUE 2.26K
J 0
(245 4900);
DISPLAY 0.617021 (245 4900);
PAINT SKYBLUE (245 4900);
FORCEPROP 1 LASTPIN (200 4725) $PN 2
J 0
(205 4735);
DISPLAY 0.787234 (205 4735);
PAINT ORANGE (205 4735);
FORCEPROP 1 LASTPIN (200 4925) $PN 1
J 0
(205 4887);
DISPLAY 0.787234 (205 4887);
PAINT ORANGE (205 4887);
FORCEPROP 1 LAST LOCATION R2U13
J 0
(245 4950);
DISPLAY 0.617021 (245 4950);
PAINT AQUA (245 4950);
FORCEPROP 2 LAST SEC_TYPE 0402
J 0
(250 5050);
DISPLAY 1.021277 (250 5050);
PAINT ORANGE (250 5050);
DISPLAY INVISIBLE (250 5050);
FORCEPROP 2 LAST SEC 1
J 0
(250 5050);
PAINT MONO (250 5050);
DISPLAY INVISIBLE (250 5050);
FORCEPROP 0 LAST BOM_COST SM_CONTROLLER
J 0
(250 5150);
DISPLAY 1.021277 (250 5150);
PAINT ORANGE (250 5150);
DISPLAY INVISIBLE (250 5150);
FORCEPROP 1 LAST PATH I216
J 0
(250 5000);
DISPLAY 0.978723 (250 5000);
PAINT WHITE (250 5000);
DISPLAY INVISIBLE (250 5000);
FORCEPROP 0 LAST ROOM SMBUS
J 0
(250 5050);
DISPLAY 1.021277 (250 5050);
PAINT ORANGE (250 5050);
DISPLAY INVISIBLE (250 5050);
FORCEPROP 0 LAST SKU B
J 0
(250 5050);
DISPLAY 1.021277 (250 5050);
PAINT ORANGE (250 5050);
DISPLAY INVISIBLE (250 5050);
FORCEPROP 2 LAST CDS_LOCATION R2U13
J 0
(245 4950);
DISPLAY 0.617021 (245 4950);
PAINT AQUA (245 4950);
DISPLAY INVISIBLE (245 4950);
FORCEPROP 2 LAST CDS_LIB mstr_discrete
J 0
(200 4825);
PAINT ORANGE (200 4825);
DISPLAY INVISIBLE (200 4825);
FORCEADD RES..1
(700 3375);
FORCEPROP 1 LAST VALUE 20.0
J 2
(1000 3375);
DISPLAY 0.617021 (1000 3375);
PAINT SKYBLUE (1000 3375);
FORCEPROP 1 LASTPIN (800 3375) $PN 2
J 0
(762 3387);
DISPLAY 0.617021 (762 3387);
PAINT MONO (762 3387);
FORCEPROP 1 LAST MATERIAL CHIP
J 0
(500 3375);
DISPLAY 0.617021 (500 3375);
PAINT SKYBLUE (500 3375);
FORCEPROP 1 LASTPIN (600 3375) $PN 1
J 0
(612 3387);
DISPLAY 0.617021 (612 3387);
PAINT MONO (612 3387);
FORCEPROP 1 LAST LOCATION R2U1
J 0
(500 3425);
DISPLAY 0.617021 (500 3425);
PAINT AQUA (500 3425);
FORCEPROP 1 LAST PACK_TYPE 0402
J 0
(900 3425);
DISPLAY 0.638298 (900 3425);
PAINT SKYBLUE (900 3425);
FORCEPROP 1 LAST WATTAGE 1/16W
J 0
(1050 3425);
DISPLAY 0.638298 (1050 3425);
PAINT SKYBLUE (1050 3425);
FORCEPROP 1 LAST PART_NUMBER G21796-173
J 0
(650 3425);
DISPLAY 0.638298 (650 3425);
PAINT BLUE (650 3425);
FORCEPROP 1 LAST TOLERANCE 1%
J 0
(825 3375);
DISPLAY 0.617021 (825 3375);
PAINT SKYBLUE (825 3375);
FORCEPROP 2 LAST CDS_SEC 1
J 0
(650 3575);
DISPLAY 1.404255 (650 3575);
PAINT ORANGE (650 3575);
DISPLAY INVISIBLE (650 3575);
FORCEPROP 2 LAST $SEC 1
J 0
(650 3575);
DISPLAY 0.936170 (650 3575);
PAINT MONO (650 3575);
DISPLAY INVISIBLE (650 3575);
FORCEPROP 2 LAST BOM_COST SM_CONTROLLER
J 0
(650 3525);
DISPLAY 1.021277 (650 3525);
PAINT ORANGE (650 3525);
DISPLAY INVISIBLE (650 3525);
FORCEPROP 1 LAST PATH I218
J 0
(650 3525);
DISPLAY 0.978723 (650 3525);
PAINT WHITE (650 3525);
DISPLAY INVISIBLE (650 3525);
FORCEPROP 2 LAST ROOM SMBUS
J 0
(650 3475);
DISPLAY 1.021277 (650 3475);
PAINT ORANGE (650 3475);
DISPLAY INVISIBLE (650 3475);
FORCEPROP 2 LAST CDS_LIB mstr_discrete
J 0
(700 3375);
PAINT ORANGE (700 3375);
DISPLAY INVISIBLE (700 3375);
FORCEPROP 2 LAST CDS_LOCATION R2U1
J 0
(650 3425);
DISPLAY 0.617021 (650 3425);
PAINT AQUA (650 3425);
DISPLAY INVISIBLE (650 3425);
FORCEADD RES..1
(700 3550);
FORCEPROP 1 LAST MATERIAL CHIP
J 0
(500 3550);
DISPLAY 0.617021 (500 3550);
PAINT SKYBLUE (500 3550);
FORCEPROP 1 LAST LOCATION R2T49
J 0
(500 3600);
DISPLAY 0.617021 (500 3600);
PAINT AQUA (500 3600);
FORCEPROP 1 LASTPIN (600 3550) $PN 1
J 0
(612 3562);
DISPLAY 0.617021 (612 3562);
PAINT MONO (612 3562);
FORCEPROP 1 LAST WATTAGE 1/16W
J 0
(1050 3600);
DISPLAY 0.638298 (1050 3600);
PAINT SKYBLUE (1050 3600);
FORCEPROP 1 LAST PACK_TYPE 0402
J 0
(900 3600);
DISPLAY 0.638298 (900 3600);
PAINT SKYBLUE (900 3600);
FORCEPROP 1 LAST VALUE 20.0
J 2
(1000 3550);
DISPLAY 0.617021 (1000 3550);
PAINT SKYBLUE (1000 3550);
FORCEPROP 1 LASTPIN (800 3550) $PN 2
J 0
(762 3562);
DISPLAY 0.617021 (762 3562);
PAINT MONO (762 3562);
FORCEPROP 1 LAST PART_NUMBER G21796-173
J 0
(650 3600);
DISPLAY 0.638298 (650 3600);
PAINT BLUE (650 3600);
FORCEPROP 1 LAST TOLERANCE 1%
J 0
(825 3550);
DISPLAY 0.617021 (825 3550);
PAINT SKYBLUE (825 3550);
FORCEPROP 2 LAST BOM_COST SM_CONTROLLER
J 0
(650 3700);
DISPLAY 1.021277 (650 3700);
PAINT ORANGE (650 3700);
DISPLAY INVISIBLE (650 3700);
FORCEPROP 2 LAST CDS_SEC 1
J 0
(650 3750);
DISPLAY 1.404255 (650 3750);
PAINT ORANGE (650 3750);
DISPLAY INVISIBLE (650 3750);
FORCEPROP 2 LAST $SEC 1
J 0
(650 3750);
DISPLAY 0.936170 (650 3750);
PAINT MONO (650 3750);
DISPLAY INVISIBLE (650 3750);
FORCEPROP 2 LAST CDS_LOCATION R2T49
J 0
(650 3600);
DISPLAY 0.617021 (650 3600);
PAINT AQUA (650 3600);
DISPLAY INVISIBLE (650 3600);
FORCEPROP 1 LAST PATH I219
J 0
(650 3700);
DISPLAY 0.978723 (650 3700);
PAINT WHITE (650 3700);
DISPLAY INVISIBLE (650 3700);
FORCEPROP 2 LAST ROOM SMBUS
J 0
(650 3650);
DISPLAY 1.021277 (650 3650);
PAINT ORANGE (650 3650);
DISPLAY INVISIBLE (650 3650);
FORCEPROP 2 LAST CDS_LIB mstr_discrete
J 0
(700 3550);
PAINT ORANGE (700 3550);
DISPLAY INVISIBLE (700 3550);
FORCEADD RES..1
(800 4275);
FORCEPROP 1 LAST VALUE 20.0
J 2
(1100 4275);
DISPLAY 0.617021 (1100 4275);
PAINT SKYBLUE (1100 4275);
FORCEPROP 1 LAST PACK_TYPE 0402
J 0
(1000 4325);
DISPLAY 0.638298 (1000 4325);
PAINT SKYBLUE (1000 4325);
FORCEPROP 1 LAST PART_NUMBER G21796-173
J 0
(750 4325);
DISPLAY 0.638298 (750 4325);
PAINT BLUE (750 4325);
FORCEPROP 1 LAST TOLERANCE 1%
J 0
(925 4275);
DISPLAY 0.617021 (925 4275);
PAINT SKYBLUE (925 4275);
FORCEPROP 1 LAST MATERIAL CHIP
J 0
(600 4275);
DISPLAY 0.617021 (600 4275);
PAINT SKYBLUE (600 4275);
FORCEPROP 1 LAST LOCATION R2U7
J 0
(600 4325);
DISPLAY 0.617021 (600 4325);
PAINT AQUA (600 4325);
FORCEPROP 1 LASTPIN (900 4275) $PN 2
J 0
(862 4287);
DISPLAY 0.617021 (862 4287);
PAINT MONO (862 4287);
FORCEPROP 1 LASTPIN (700 4275) $PN 1
J 0
(712 4287);
DISPLAY 0.617021 (712 4287);
PAINT MONO (712 4287);
FORCEPROP 1 LAST WATTAGE 1/16W
J 0
(1200 4325);
DISPLAY 0.638298 (1200 4325);
PAINT SKYBLUE (1200 4325);
FORCEPROP 2 LAST CDS_LOCATION R2U7
J 0
(750 4325);
DISPLAY 0.617021 (750 4325);
PAINT AQUA (750 4325);
DISPLAY INVISIBLE (750 4325);
FORCEPROP 2 LAST ROOM SMBUS
J 0
(750 4375);
DISPLAY 1.021277 (750 4375);
PAINT ORANGE (750 4375);
DISPLAY INVISIBLE (750 4375);
FORCEPROP 2 LAST BOM_COST SM_CONTROLLER
J 0
(750 4425);
DISPLAY 1.021277 (750 4425);
PAINT ORANGE (750 4425);
DISPLAY INVISIBLE (750 4425);
FORCEPROP 2 LAST CDS_SEC 1
J 0
(750 4475);
DISPLAY 1.404255 (750 4475);
PAINT ORANGE (750 4475);
DISPLAY INVISIBLE (750 4475);
FORCEPROP 2 LAST $SEC 1
J 0
(750 4475);
DISPLAY 0.936170 (750 4475);
PAINT MONO (750 4475);
DISPLAY INVISIBLE (750 4475);
FORCEPROP 1 LAST PATH I220
J 0
(750 4425);
DISPLAY 0.978723 (750 4425);
PAINT WHITE (750 4425);
DISPLAY INVISIBLE (750 4425);
FORCEPROP 2 LAST CDS_LIB mstr_discrete
J 0
(800 4275);
PAINT ORANGE (800 4275);
DISPLAY INVISIBLE (800 4275);
FORCEADD RES..1
(800 4450);
FORCEPROP 1 LAST TOLERANCE 1%
J 0
(925 4450);
DISPLAY 0.617021 (925 4450);
PAINT SKYBLUE (925 4450);
FORCEPROP 1 LAST PART_NUMBER G21796-173
J 0
(750 4500);
DISPLAY 0.638298 (750 4500);
PAINT BLUE (750 4500);
FORCEPROP 1 LAST PACK_TYPE 0402
J 0
(1000 4500);
DISPLAY 0.638298 (1000 4500);
PAINT SKYBLUE (1000 4500);
FORCEPROP 1 LAST LOCATION R2U10
J 0
(600 4500);
DISPLAY 0.617021 (600 4500);
PAINT AQUA (600 4500);
FORCEPROP 1 LASTPIN (900 4450) $PN 2
J 0
(862 4462);
DISPLAY 0.617021 (862 4462);
PAINT MONO (862 4462);
FORCEPROP 1 LASTPIN (700 4450) $PN 1
J 0
(712 4462);
DISPLAY 0.617021 (712 4462);
PAINT MONO (712 4462);
FORCEPROP 1 LAST MATERIAL CHIP
J 0
(600 4450);
DISPLAY 0.617021 (600 4450);
PAINT SKYBLUE (600 4450);
FORCEPROP 1 LAST VALUE 20.0
J 0
(1100 4450);
DISPLAY 0.617021 (1100 4450);
PAINT SKYBLUE (1100 4450);
FORCEPROP 1 LAST WATTAGE 1/16W
J 0
(1200 4500);
DISPLAY 0.638298 (1200 4500);
PAINT SKYBLUE (1200 4500);
FORCEPROP 2 LAST ROOM SMBUS
J 0
(750 4550);
DISPLAY 1.021277 (750 4550);
PAINT ORANGE (750 4550);
DISPLAY INVISIBLE (750 4550);
FORCEPROP 2 LAST CDS_LOCATION R2U10
J 0
(750 4500);
DISPLAY 0.617021 (750 4500);
PAINT AQUA (750 4500);
DISPLAY INVISIBLE (750 4500);
FORCEPROP 1 LAST PATH I221
J 0
(750 4600);
DISPLAY 0.978723 (750 4600);
PAINT WHITE (750 4600);
DISPLAY INVISIBLE (750 4600);
FORCEPROP 2 LAST BOM_COST SM_CONTROLLER
J 0
(750 4600);
DISPLAY 1.021277 (750 4600);
PAINT ORANGE (750 4600);
DISPLAY INVISIBLE (750 4600);
FORCEPROP 2 LAST $SEC 1
J 0
(750 4650);
DISPLAY 0.936170 (750 4650);
PAINT MONO (750 4650);
DISPLAY INVISIBLE (750 4650);
FORCEPROP 2 LAST CDS_SEC 1
J 0
(750 4650);
DISPLAY 1.404255 (750 4650);
PAINT ORANGE (750 4650);
DISPLAY INVISIBLE (750 4650);
FORCEPROP 2 LAST CDS_LIB mstr_discrete
J 0
(800 4450);
PAINT ORANGE (800 4450);
DISPLAY INVISIBLE (800 4450);
FORCEADD RES..1
(700 1600);
FORCEPROP 1 LASTPIN (600 1600) $PN 1
J 0
(612 1612);
DISPLAY 0.617021 (612 1612);
PAINT MONO (612 1612);
FORCEPROP 1 LAST MATERIAL CHIP
J 0
(500 1600);
DISPLAY 0.617021 (500 1600);
PAINT SKYBLUE (500 1600);
FORCEPROP 1 LAST LOCATION R1U11
J 0
(500 1675);
DISPLAY 0.617021 (500 1675);
PAINT AQUA (500 1675);
FORCEPROP 1 LAST PART_NUMBER G21497-005
J 0
(650 1675);
DISPLAY 0.638298 (650 1675);
PAINT BLUE (650 1675);
FORCEPROP 1 LAST WATTAGE 1/16W
J 0
(1050 1675);
DISPLAY 0.638298 (1050 1675);
PAINT SKYBLUE (1050 1675);
FORCEPROP 1 LAST PACK_TYPE 0402
J 0
(900 1675);
DISPLAY 0.638298 (900 1675);
PAINT SKYBLUE (900 1675);
FORCEPROP 1 LASTPIN (800 1600) $PN 2
J 0
(762 1612);
DISPLAY 0.617021 (762 1612);
PAINT MONO (762 1612);
FORCEPROP 1 LAST VALUE 0.0
J 2
(1000 1600);
DISPLAY 0.617021 (1000 1600);
PAINT SKYBLUE (1000 1600);
FORCEPROP 1 LAST TOLERANCE 5%
J 0
(825 1600);
DISPLAY 0.617021 (825 1600);
PAINT SKYBLUE (825 1600);
FORCEPROP 2 LAST CDS_SEC 1
J 0
(650 1800);
DISPLAY 1.404255 (650 1800);
PAINT ORANGE (650 1800);
DISPLAY INVISIBLE (650 1800);
FORCEPROP 2 LAST $SEC 1
J 0
(650 1800);
DISPLAY 0.936170 (650 1800);
PAINT MONO (650 1800);
DISPLAY INVISIBLE (650 1800);
FORCEPROP 2 LAST BOM_COST SM_CONTROLLER
J 0
(650 1750);
DISPLAY 1.021277 (650 1750);
PAINT ORANGE (650 1750);
DISPLAY INVISIBLE (650 1750);
FORCEPROP 1 LAST PATH I222
J 0
(650 1750);
DISPLAY 0.978723 (650 1750);
PAINT WHITE (650 1750);
DISPLAY INVISIBLE (650 1750);
FORCEPROP 2 LAST ROOM SMBUS
J 0
(650 1700);
DISPLAY 1.021277 (650 1700);
PAINT ORANGE (650 1700);
DISPLAY INVISIBLE (650 1700);
FORCEPROP 2 LAST CDS_LOCATION R1U11
J 0
(650 1650);
DISPLAY 0.617021 (650 1650);
PAINT AQUA (650 1650);
DISPLAY INVISIBLE (650 1650);
FORCEPROP 2 LAST CDS_LIB mstr_discrete
J 0
(700 1600);
PAINT ORANGE (700 1600);
DISPLAY INVISIBLE (700 1600);
FORCEADD RES..1
(700 1775);
FORCEPROP 1 LAST MATERIAL CHIP
J 0
(500 1775);
DISPLAY 0.617021 (500 1775);
PAINT SKYBLUE (500 1775);
FORCEPROP 1 LASTPIN (800 1775) $PN 2
J 0
(762 1787);
DISPLAY 0.617021 (762 1787);
PAINT MONO (762 1787);
FORCEPROP 1 LAST LOCATION R1U8
J 0
(500 1850);
DISPLAY 0.617021 (500 1850);
PAINT AQUA (500 1850);
FORCEPROP 1 LAST TOLERANCE 5%
J 0
(825 1775);
DISPLAY 0.617021 (825 1775);
PAINT SKYBLUE (825 1775);
FORCEPROP 1 LASTPIN (600 1775) $PN 1
J 0
(612 1787);
DISPLAY 0.617021 (612 1787);
PAINT MONO (612 1787);
FORCEPROP 1 LAST PART_NUMBER G21497-005
J 0
(650 1850);
DISPLAY 0.638298 (650 1850);
PAINT BLUE (650 1850);
FORCEPROP 1 LAST VALUE 0.0
J 2
(1000 1775);
DISPLAY 0.617021 (1000 1775);
PAINT SKYBLUE (1000 1775);
FORCEPROP 1 LAST WATTAGE 1/16W
J 0
(1050 1850);
DISPLAY 0.638298 (1050 1850);
PAINT SKYBLUE (1050 1850);
FORCEPROP 1 LAST PACK_TYPE 0402
J 0
(900 1850);
DISPLAY 0.638298 (900 1850);
PAINT SKYBLUE (900 1850);
FORCEPROP 2 LAST BOM_COST SM_CONTROLLER
J 0
(650 1925);
DISPLAY 1.021277 (650 1925);
PAINT ORANGE (650 1925);
DISPLAY INVISIBLE (650 1925);
FORCEPROP 2 LAST CDS_SEC 1
J 0
(650 1975);
DISPLAY 1.404255 (650 1975);
PAINT ORANGE (650 1975);
DISPLAY INVISIBLE (650 1975);
FORCEPROP 2 LAST $SEC 1
J 0
(650 1975);
DISPLAY 0.936170 (650 1975);
PAINT MONO (650 1975);
DISPLAY INVISIBLE (650 1975);
FORCEPROP 2 LAST CDS_LOCATION R1U8
J 0
(650 1825);
DISPLAY 0.617021 (650 1825);
PAINT AQUA (650 1825);
DISPLAY INVISIBLE (650 1825);
FORCEPROP 1 LAST PATH I223
J 0
(650 1925);
DISPLAY 0.978723 (650 1925);
PAINT WHITE (650 1925);
DISPLAY INVISIBLE (650 1925);
FORCEPROP 2 LAST ROOM SMBUS
J 0
(650 1875);
DISPLAY 1.021277 (650 1875);
PAINT ORANGE (650 1875);
DISPLAY INVISIBLE (650 1875);
FORCEPROP 2 LAST CDS_LIB mstr_discrete
J 0
(700 1775);
PAINT ORANGE (700 1775);
DISPLAY INVISIBLE (700 1775);
FORCEADD RES..1
(-3625 1575);
FORCEPROP 1 LAST MATERIAL CHIP
J 0
(-3825 1575);
DISPLAY 0.617021 (-3825 1575);
PAINT SKYBLUE (-3825 1575);
FORCEPROP 1 LAST TOLERANCE 1%
J 0
(-3500 1575);
DISPLAY 0.617021 (-3500 1575);
PAINT SKYBLUE (-3500 1575);
FORCEPROP 1 LASTPIN (-3725 1575) $PN 1
J 0
(-3713 1587);
DISPLAY 0.617021 (-3713 1587);
PAINT MONO (-3713 1587);
FORCEPROP 1 LAST PART_NUMBER G21796-173
J 0
(-3700 1625);
DISPLAY 0.638298 (-3700 1625);
PAINT BLUE (-3700 1625);
FORCEPROP 1 LASTPIN (-3525 1575) $PN 2
J 0
(-3563 1587);
DISPLAY 0.617021 (-3563 1587);
PAINT MONO (-3563 1587);
FORCEPROP 1 LAST VALUE 20.0
J 2
(-3325 1575);
DISPLAY 0.617021 (-3325 1575);
PAINT SKYBLUE (-3325 1575);
FORCEPROP 1 LAST WATTAGE 1/16W
J 0
(-3425 1625);
DISPLAY 0.638298 (-3425 1625);
PAINT SKYBLUE (-3425 1625);
FORCEPROP 1 LAST PACK_TYPE 0402
J 0
(-3250 1625);
DISPLAY 0.638298 (-3250 1625);
PAINT SKYBLUE (-3250 1625);
FORCEPROP 1 LAST LOCATION R9G12
J 0
(-3850 1625);
DISPLAY 0.617021 (-3850 1625);
PAINT AQUA (-3850 1625);
FORCEPROP 2 LAST CDS_SEC 1
J 0
(-3675 1775);
DISPLAY 1.404255 (-3675 1775);
PAINT ORANGE (-3675 1775);
DISPLAY INVISIBLE (-3675 1775);
FORCEPROP 2 LAST $SEC 1
J 0
(-3675 1775);
DISPLAY 0.936170 (-3675 1775);
PAINT MONO (-3675 1775);
DISPLAY INVISIBLE (-3675 1775);
FORCEPROP 1 LAST PATH I224
J 0
(-3675 1725);
DISPLAY 0.978723 (-3675 1725);
PAINT WHITE (-3675 1725);
DISPLAY INVISIBLE (-3675 1725);
FORCEPROP 2 LAST ROOM SMBUS
J 0
(-3675 1675);
DISPLAY 1.021277 (-3675 1675);
PAINT ORANGE (-3675 1675);
DISPLAY INVISIBLE (-3675 1675);
FORCEPROP 2 LAST BOM_COST SM_CONTROLLER
J 0
(-3675 1725);
DISPLAY 1.021277 (-3675 1725);
PAINT ORANGE (-3675 1725);
DISPLAY INVISIBLE (-3675 1725);
FORCEPROP 2 LAST CDS_LIB mstr_discrete
J 0
(-3625 1575);
PAINT ORANGE (-3625 1575);
DISPLAY INVISIBLE (-3625 1575);
FORCEPROP 2 LAST CDS_LOCATION R9G12
J 0
(-3675 1625);
DISPLAY 0.617021 (-3675 1625);
PAINT AQUA (-3675 1625);
DISPLAY INVISIBLE (-3675 1625);
FORCEADD RES..1
(-3625 1450);
FORCEPROP 1 LAST LOCATION R1U20
J 0
(-3850 1500);
DISPLAY 0.617021 (-3850 1500);
PAINT AQUA (-3850 1500);
FORCEPROP 1 LASTPIN (-3525 1450) $PN 2
J 0
(-3563 1462);
DISPLAY 0.617021 (-3563 1462);
PAINT MONO (-3563 1462);
FORCEPROP 1 LAST TOLERANCE 1%
J 0
(-3500 1450);
DISPLAY 0.617021 (-3500 1450);
PAINT SKYBLUE (-3500 1450);
FORCEPROP 1 LAST PART_NUMBER G21796-173
J 0
(-3700 1500);
DISPLAY 0.638298 (-3700 1500);
PAINT BLUE (-3700 1500);
FORCEPROP 1 LASTPIN (-3725 1450) $PN 1
J 0
(-3713 1462);
DISPLAY 0.617021 (-3713 1462);
PAINT MONO (-3713 1462);
FORCEPROP 1 LAST MATERIAL CHIP
J 0
(-3825 1450);
DISPLAY 0.617021 (-3825 1450);
PAINT SKYBLUE (-3825 1450);
FORCEPROP 1 LAST VALUE 20.0
J 2
(-3325 1450);
DISPLAY 0.617021 (-3325 1450);
PAINT SKYBLUE (-3325 1450);
FORCEPROP 1 LAST WATTAGE 1/16W
J 0
(-3425 1500);
DISPLAY 0.638298 (-3425 1500);
PAINT SKYBLUE (-3425 1500);
FORCEPROP 1 LAST PACK_TYPE 0402
J 0
(-3250 1500);
DISPLAY 0.638298 (-3250 1500);
PAINT SKYBLUE (-3250 1500);
FORCEPROP 2 LAST CDS_SEC 1
J 0
(-3675 1650);
DISPLAY 1.404255 (-3675 1650);
PAINT ORANGE (-3675 1650);
DISPLAY INVISIBLE (-3675 1650);
FORCEPROP 2 LAST $SEC 1
J 0
(-3675 1650);
DISPLAY 0.936170 (-3675 1650);
PAINT MONO (-3675 1650);
DISPLAY INVISIBLE (-3675 1650);
FORCEPROP 2 LAST BOM_COST SM_CONTROLLER
J 0
(-3675 1600);
DISPLAY 1.021277 (-3675 1600);
PAINT ORANGE (-3675 1600);
DISPLAY INVISIBLE (-3675 1600);
FORCEPROP 1 LAST PATH I225
J 0
(-3675 1600);
DISPLAY 0.978723 (-3675 1600);
PAINT WHITE (-3675 1600);
DISPLAY INVISIBLE (-3675 1600);
FORCEPROP 2 LAST ROOM SMBUS
J 0
(-3675 1550);
DISPLAY 1.021277 (-3675 1550);
PAINT ORANGE (-3675 1550);
DISPLAY INVISIBLE (-3675 1550);
FORCEPROP 2 LAST CDS_LIB mstr_discrete
J 0
(-3625 1450);
PAINT ORANGE (-3625 1450);
DISPLAY INVISIBLE (-3625 1450);
FORCEPROP 2 LAST CDS_LOCATION R1U20
J 0
(-3675 1500);
DISPLAY 0.617021 (-3675 1500);
PAINT AQUA (-3675 1500);
DISPLAY INVISIBLE (-3675 1500);
FORCEADD RES..1
(-3625 1325);
FORCEPROP 1 LASTPIN (-3525 1325) $PN 2
J 0
(-3563 1337);
DISPLAY 0.617021 (-3563 1337);
PAINT MONO (-3563 1337);
FORCEPROP 1 LAST TOLERANCE 1%
J 0
(-3500 1325);
DISPLAY 0.617021 (-3500 1325);
PAINT SKYBLUE (-3500 1325);
FORCEPROP 1 LAST LOCATION R1U19
J 0
(-3850 1375);
DISPLAY 0.617021 (-3850 1375);
PAINT AQUA (-3850 1375);
FORCEPROP 1 LASTPIN (-3725 1325) $PN 1
J 0
(-3713 1337);
DISPLAY 0.617021 (-3713 1337);
PAINT MONO (-3713 1337);
FORCEPROP 1 LAST MATERIAL CHIP
J 0
(-3825 1325);
DISPLAY 0.617021 (-3825 1325);
PAINT SKYBLUE (-3825 1325);
FORCEPROP 1 LAST PART_NUMBER G21796-173
J 0
(-3700 1375);
DISPLAY 0.638298 (-3700 1375);
PAINT BLUE (-3700 1375);
FORCEPROP 1 LAST PACK_TYPE 0402
J 0
(-3250 1375);
DISPLAY 0.638298 (-3250 1375);
PAINT SKYBLUE (-3250 1375);
FORCEPROP 1 LAST VALUE 20.0
J 2
(-3325 1325);
DISPLAY 0.617021 (-3325 1325);
PAINT SKYBLUE (-3325 1325);
FORCEPROP 1 LAST WATTAGE 1/16W
J 0
(-3425 1375);
DISPLAY 0.638298 (-3425 1375);
PAINT SKYBLUE (-3425 1375);
FORCEPROP 2 LAST CDS_SEC 1
J 0
(-3675 1525);
DISPLAY 1.404255 (-3675 1525);
PAINT ORANGE (-3675 1525);
DISPLAY INVISIBLE (-3675 1525);
FORCEPROP 2 LAST $SEC 1
J 0
(-3675 1525);
DISPLAY 0.936170 (-3675 1525);
PAINT MONO (-3675 1525);
DISPLAY INVISIBLE (-3675 1525);
FORCEPROP 2 LAST BOM_COST SM_CONTROLLER
J 0
(-3675 1475);
DISPLAY 1.021277 (-3675 1475);
PAINT ORANGE (-3675 1475);
DISPLAY INVISIBLE (-3675 1475);
FORCEPROP 1 LAST PATH I226
J 0
(-3675 1475);
DISPLAY 0.978723 (-3675 1475);
PAINT WHITE (-3675 1475);
DISPLAY INVISIBLE (-3675 1475);
FORCEPROP 2 LAST ROOM SMBUS
J 0
(-3675 1425);
DISPLAY 1.021277 (-3675 1425);
PAINT ORANGE (-3675 1425);
DISPLAY INVISIBLE (-3675 1425);
FORCEPROP 2 LAST CDS_LIB mstr_discrete
J 0
(-3625 1325);
PAINT ORANGE (-3625 1325);
DISPLAY INVISIBLE (-3625 1325);
FORCEPROP 2 LAST CDS_LOCATION R1U19
J 0
(-3675 1375);
DISPLAY 0.617021 (-3675 1375);
PAINT AQUA (-3675 1375);
DISPLAY INVISIBLE (-3675 1375);
FORCEADD RES..1
(-3625 1200);
FORCEPROP 1 LAST TOLERANCE 1%
J 0
(-3500 1200);
DISPLAY 0.617021 (-3500 1200);
PAINT SKYBLUE (-3500 1200);
FORCEPROP 1 LAST LOCATION R9G13
J 0
(-3850 1250);
DISPLAY 0.617021 (-3850 1250);
PAINT AQUA (-3850 1250);
FORCEPROP 1 LASTPIN (-3525 1200) $PN 2
J 0
(-3563 1212);
DISPLAY 0.617021 (-3563 1212);
PAINT MONO (-3563 1212);
FORCEPROP 1 LAST MATERIAL CHIP
J 0
(-3825 1200);
DISPLAY 0.617021 (-3825 1200);
PAINT SKYBLUE (-3825 1200);
FORCEPROP 1 LASTPIN (-3725 1200) $PN 1
J 0
(-3713 1212);
DISPLAY 0.617021 (-3713 1212);
PAINT MONO (-3713 1212);
FORCEPROP 1 LAST PART_NUMBER G21796-173
J 0
(-3700 1250);
DISPLAY 0.638298 (-3700 1250);
PAINT BLUE (-3700 1250);
FORCEPROP 1 LAST VALUE 20.0
J 2
(-3325 1200);
DISPLAY 0.617021 (-3325 1200);
PAINT SKYBLUE (-3325 1200);
FORCEPROP 1 LAST PACK_TYPE 0402
J 0
(-3250 1250);
DISPLAY 0.638298 (-3250 1250);
PAINT SKYBLUE (-3250 1250);
FORCEPROP 1 LAST WATTAGE 1/16W
J 0
(-3425 1250);
DISPLAY 0.638298 (-3425 1250);
PAINT SKYBLUE (-3425 1250);
FORCEPROP 2 LAST CDS_SEC 1
J 0
(-3675 1400);
DISPLAY 1.404255 (-3675 1400);
PAINT ORANGE (-3675 1400);
DISPLAY INVISIBLE (-3675 1400);
FORCEPROP 2 LAST $SEC 1
J 0
(-3675 1400);
DISPLAY 0.936170 (-3675 1400);
PAINT MONO (-3675 1400);
DISPLAY INVISIBLE (-3675 1400);
FORCEPROP 2 LAST ROOM SMBUS
J 0
(-3675 1300);
DISPLAY 1.021277 (-3675 1300);
PAINT ORANGE (-3675 1300);
DISPLAY INVISIBLE (-3675 1300);
FORCEPROP 1 LAST PATH I227
J 0
(-3675 1350);
DISPLAY 0.978723 (-3675 1350);
PAINT WHITE (-3675 1350);
DISPLAY INVISIBLE (-3675 1350);
FORCEPROP 2 LAST BOM_COST SM_CONTROLLER
J 0
(-3675 1350);
DISPLAY 1.021277 (-3675 1350);
PAINT ORANGE (-3675 1350);
DISPLAY INVISIBLE (-3675 1350);
FORCEPROP 2 LAST CDS_LIB mstr_discrete
J 0
(-3625 1200);
PAINT ORANGE (-3625 1200);
DISPLAY INVISIBLE (-3625 1200);
FORCEPROP 2 LAST CDS_LOCATION R9G13
J 0
(-3675 1250);
DISPLAY 0.617021 (-3675 1250);
PAINT AQUA (-3675 1250);
DISPLAY INVISIBLE (-3675 1250);
FORCEADD RES..1
(-2875 2525);
FORCEPROP 1 LAST MATERIAL CHIP
J 0
(-3075 2525);
DISPLAY 0.617021 (-3075 2525);
PAINT SKYBLUE (-3075 2525);
FORCEPROP 1 LASTPIN (-2775 2525) $PN 2
J 0
(-2813 2537);
DISPLAY 0.617021 (-2813 2537);
PAINT MONO (-2813 2537);
FORCEPROP 1 LASTPIN (-2975 2525) $PN 1
J 0
(-2963 2537);
DISPLAY 0.617021 (-2963 2537);
PAINT MONO (-2963 2537);
FORCEPROP 1 LAST LOCATION R8G5
J 0
(-3100 2575);
DISPLAY 0.617021 (-3100 2575);
PAINT AQUA (-3100 2575);
FORCEPROP 1 LAST PART_NUMBER G21796-173
J 0
(-2950 2575);
DISPLAY 0.638298 (-2950 2575);
PAINT BLUE (-2950 2575);
FORCEPROP 1 LAST WATTAGE 1/16W
J 0
(-2650 2575);
DISPLAY 0.638298 (-2650 2575);
PAINT SKYBLUE (-2650 2575);
FORCEPROP 1 LAST VALUE 20.0
J 2
(-2575 2525);
DISPLAY 0.617021 (-2575 2525);
PAINT SKYBLUE (-2575 2525);
FORCEPROP 1 LAST TOLERANCE 1%
J 0
(-2750 2525);
DISPLAY 0.617021 (-2750 2525);
PAINT SKYBLUE (-2750 2525);
FORCEPROP 1 LAST PACK_TYPE 0402
J 0
(-2450 2575);
DISPLAY 0.638298 (-2450 2575);
PAINT SKYBLUE (-2450 2575);
FORCEPROP 2 LAST BOM_COST SM_CONTROLLER
J 0
(-2925 2675);
DISPLAY 1.021277 (-2925 2675);
PAINT ORANGE (-2925 2675);
DISPLAY INVISIBLE (-2925 2675);
FORCEPROP 2 LAST CDS_SEC 1
J 0
(-2925 2725);
DISPLAY 1.404255 (-2925 2725);
PAINT ORANGE (-2925 2725);
DISPLAY INVISIBLE (-2925 2725);
FORCEPROP 2 LAST $SEC 1
J 0
(-2925 2725);
DISPLAY 0.936170 (-2925 2725);
PAINT MONO (-2925 2725);
DISPLAY INVISIBLE (-2925 2725);
FORCEPROP 2 LAST CDS_LOCATION R8G5
J 0
(-2925 2575);
DISPLAY 0.617021 (-2925 2575);
PAINT AQUA (-2925 2575);
DISPLAY INVISIBLE (-2925 2575);
FORCEPROP 1 LAST PATH I228
J 0
(-2925 2675);
DISPLAY 0.978723 (-2925 2675);
PAINT WHITE (-2925 2675);
DISPLAY INVISIBLE (-2925 2675);
FORCEPROP 2 LAST ROOM SMBUS
J 0
(-2925 2625);
DISPLAY 1.021277 (-2925 2625);
PAINT ORANGE (-2925 2625);
DISPLAY INVISIBLE (-2925 2625);
FORCEPROP 2 LAST CDS_LIB mstr_discrete
J 0
(-2875 2525);
PAINT ORANGE (-2875 2525);
DISPLAY INVISIBLE (-2875 2525);
FORCEADD RES..1
(-2875 2350);
FORCEPROP 1 LASTPIN (-2975 2350) $PN 1
J 0
(-2963 2362);
DISPLAY 0.617021 (-2963 2362);
PAINT MONO (-2963 2362);
FORCEPROP 1 LAST MATERIAL CHIP
J 0
(-3075 2350);
DISPLAY 0.617021 (-3075 2350);
PAINT SKYBLUE (-3075 2350);
FORCEPROP 1 LAST TOLERANCE 1%
J 0
(-2750 2350);
DISPLAY 0.617021 (-2750 2350);
PAINT SKYBLUE (-2750 2350);
FORCEPROP 1 LAST LOCATION R8G4
J 0
(-3100 2400);
DISPLAY 0.617021 (-3100 2400);
PAINT AQUA (-3100 2400);
FORCEPROP 1 LAST PART_NUMBER G21796-173
J 0
(-2950 2400);
DISPLAY 0.638298 (-2950 2400);
PAINT BLUE (-2950 2400);
FORCEPROP 1 LASTPIN (-2775 2350) $PN 2
J 0
(-2813 2362);
DISPLAY 0.617021 (-2813 2362);
PAINT MONO (-2813 2362);
FORCEPROP 1 LAST WATTAGE 1/16W
J 0
(-2650 2400);
DISPLAY 0.638298 (-2650 2400);
PAINT SKYBLUE (-2650 2400);
FORCEPROP 1 LAST VALUE 20.0
J 2
(-2575 2350);
DISPLAY 0.617021 (-2575 2350);
PAINT SKYBLUE (-2575 2350);
FORCEPROP 1 LAST PACK_TYPE 0402
J 0
(-2450 2400);
DISPLAY 0.638298 (-2450 2400);
PAINT SKYBLUE (-2450 2400);
FORCEPROP 2 LAST CDS_SEC 1
J 0
(-2925 2550);
DISPLAY 1.404255 (-2925 2550);
PAINT ORANGE (-2925 2550);
DISPLAY INVISIBLE (-2925 2550);
FORCEPROP 2 LAST $SEC 1
J 0
(-2925 2550);
DISPLAY 0.936170 (-2925 2550);
PAINT MONO (-2925 2550);
DISPLAY INVISIBLE (-2925 2550);
FORCEPROP 2 LAST BOM_COST SM_CONTROLLER
J 0
(-2925 2500);
DISPLAY 1.021277 (-2925 2500);
PAINT ORANGE (-2925 2500);
DISPLAY INVISIBLE (-2925 2500);
FORCEPROP 1 LAST PATH I229
J 0
(-2925 2500);
DISPLAY 0.978723 (-2925 2500);
PAINT WHITE (-2925 2500);
DISPLAY INVISIBLE (-2925 2500);
FORCEPROP 2 LAST ROOM SMBUS
J 0
(-2925 2450);
DISPLAY 1.021277 (-2925 2450);
PAINT ORANGE (-2925 2450);
DISPLAY INVISIBLE (-2925 2450);
FORCEPROP 2 LAST CDS_LIB mstr_discrete
J 0
(-2875 2350);
PAINT ORANGE (-2875 2350);
DISPLAY INVISIBLE (-2875 2350);
FORCEPROP 2 LAST CDS_LOCATION R8G4
J 0
(-2925 2400);
DISPLAY 0.617021 (-2925 2400);
PAINT AQUA (-2925 2400);
DISPLAY INVISIBLE (-2925 2400);
FORCEADD RES..1
(-3175 3600);
FORCEPROP 1 LAST TOLERANCE 1%
J 0
(-3050 3600);
DISPLAY 0.617021 (-3050 3600);
PAINT SKYBLUE (-3050 3600);
FORCEPROP 1 LASTPIN (-3075 3600) $PN 2
J 0
(-3113 3612);
DISPLAY 0.617021 (-3113 3612);
PAINT MONO (-3113 3612);
FORCEPROP 1 LAST MATERIAL CHIP
J 0
(-3375 3600);
DISPLAY 0.617021 (-3375 3600);
PAINT SKYBLUE (-3375 3600);
FORCEPROP 1 LAST VALUE 20.0
J 2
(-2875 3600);
DISPLAY 0.617021 (-2875 3600);
PAINT SKYBLUE (-2875 3600);
FORCEPROP 1 LAST PART_NUMBER G21796-173
J 0
(-3200 3650);
DISPLAY 0.638298 (-3200 3650);
PAINT BLUE (-3200 3650);
FORCEPROP 1 LAST PACK_TYPE 0402
J 0
(-2925 3650);
DISPLAY 0.638298 (-2925 3650);
PAINT SKYBLUE (-2925 3650);
FORCEPROP 1 LAST WATTAGE 1/16W
J 0
(-2750 3650);
DISPLAY 0.638298 (-2750 3650);
PAINT SKYBLUE (-2750 3650);
FORCEPROP 1 LAST LOCATION R2U34
J 0
(-3400 3650);
DISPLAY 0.617021 (-3400 3650);
PAINT AQUA (-3400 3650);
FORCEPROP 1 LASTPIN (-3275 3600) $PN 1
J 0
(-3263 3612);
DISPLAY 0.617021 (-3263 3612);
PAINT MONO (-3263 3612);
FORCEPROP 2 LAST CDS_SEC 1
J 0
(-3225 3800);
DISPLAY 1.404255 (-3225 3800);
PAINT ORANGE (-3225 3800);
DISPLAY INVISIBLE (-3225 3800);
FORCEPROP 2 LAST CDS_LIB mstr_discrete
J 0
(-3175 3600);
PAINT ORANGE (-3175 3600);
DISPLAY INVISIBLE (-3175 3600);
FORCEPROP 2 LAST BOM_COST SM_CONTROLLER
J 0
(-3225 3750);
DISPLAY 1.021277 (-3225 3750);
PAINT ORANGE (-3225 3750);
DISPLAY INVISIBLE (-3225 3750);
FORCEPROP 2 LAST $SEC 1
J 0
(-3225 3800);
DISPLAY 0.936170 (-3225 3800);
PAINT MONO (-3225 3800);
DISPLAY INVISIBLE (-3225 3800);
FORCEPROP 2 LAST CDS_LOCATION R2U34
J 0
(-3225 3650);
DISPLAY 0.617021 (-3225 3650);
PAINT AQUA (-3225 3650);
DISPLAY INVISIBLE (-3225 3650);
FORCEPROP 1 LAST PATH I230
J 0
(-3225 3750);
DISPLAY 0.978723 (-3225 3750);
PAINT WHITE (-3225 3750);
DISPLAY INVISIBLE (-3225 3750);
FORCEPROP 2 LAST ROOM SMBUS
J 0
(-3225 3700);
DISPLAY 1.021277 (-3225 3700);
PAINT ORANGE (-3225 3700);
DISPLAY INVISIBLE (-3225 3700);
FORCEADD RES..1
(-3175 3775);
FORCEPROP 1 LAST TOLERANCE 1%
J 0
(-3050 3775);
DISPLAY 0.617021 (-3050 3775);
PAINT SKYBLUE (-3050 3775);
FORCEPROP 1 LASTPIN (-3075 3775) $PN 2
J 0
(-3113 3787);
DISPLAY 0.617021 (-3113 3787);
PAINT MONO (-3113 3787);
FORCEPROP 1 LAST MATERIAL CHIP
J 0
(-3375 3775);
DISPLAY 0.617021 (-3375 3775);
PAINT SKYBLUE (-3375 3775);
FORCEPROP 1 LAST PACK_TYPE 0402
J 0
(-2900 3825);
DISPLAY 0.638298 (-2900 3825);
PAINT SKYBLUE (-2900 3825);
FORCEPROP 1 LAST WATTAGE 1/16W
J 0
(-2750 3825);
DISPLAY 0.638298 (-2750 3825);
PAINT SKYBLUE (-2750 3825);
FORCEPROP 1 LASTPIN (-3275 3775) $PN 1
J 0
(-3263 3787);
DISPLAY 0.617021 (-3263 3787);
PAINT MONO (-3263 3787);
FORCEPROP 1 LAST LOCATION R2U33
J 0
(-3400 3825);
DISPLAY 0.617021 (-3400 3825);
PAINT AQUA (-3400 3825);
FORCEPROP 1 LAST PART_NUMBER G21796-173
J 0
(-3200 3825);
DISPLAY 0.638298 (-3200 3825);
PAINT BLUE (-3200 3825);
FORCEPROP 1 LAST VALUE 20.0
J 2
(-2875 3775);
DISPLAY 0.617021 (-2875 3775);
PAINT SKYBLUE (-2875 3775);
FORCEPROP 2 LAST BOM_COST SM_CONTROLLER
J 0
(-3225 3925);
DISPLAY 1.021277 (-3225 3925);
PAINT ORANGE (-3225 3925);
DISPLAY INVISIBLE (-3225 3925);
FORCEPROP 2 LAST CDS_SEC 1
J 0
(-3225 3975);
DISPLAY 1.404255 (-3225 3975);
PAINT ORANGE (-3225 3975);
DISPLAY INVISIBLE (-3225 3975);
FORCEPROP 2 LAST $SEC 1
J 0
(-3225 3975);
DISPLAY 0.936170 (-3225 3975);
PAINT MONO (-3225 3975);
DISPLAY INVISIBLE (-3225 3975);
FORCEPROP 1 LAST PATH I231
J 0
(-3225 3925);
DISPLAY 0.978723 (-3225 3925);
PAINT WHITE (-3225 3925);
DISPLAY INVISIBLE (-3225 3925);
FORCEPROP 2 LAST ROOM SMBUS
J 0
(-3225 3875);
DISPLAY 1.021277 (-3225 3875);
PAINT ORANGE (-3225 3875);
DISPLAY INVISIBLE (-3225 3875);
FORCEPROP 2 LAST CDS_LOCATION R2U33
J 0
(-3225 3825);
DISPLAY 0.617021 (-3225 3825);
PAINT AQUA (-3225 3825);
DISPLAY INVISIBLE (-3225 3825);
FORCEPROP 2 LAST CDS_LIB mstr_discrete
J 0
(-3175 3775);
PAINT ORANGE (-3175 3775);
DISPLAY INVISIBLE (-3175 3775);
FORCEADD RES..1
(-3175 4775);
FORCEPROP 1 LAST PACK_TYPE 0402
J 0
(-2900 4825);
DISPLAY 0.638298 (-2900 4825);
PAINT SKYBLUE (-2900 4825);
FORCEPROP 1 LAST VALUE 20.0
J 2
(-2875 4775);
DISPLAY 0.617021 (-2875 4775);
PAINT SKYBLUE (-2875 4775);
FORCEPROP 1 LAST WATTAGE 1/16W
J 0
(-2750 4825);
DISPLAY 0.638298 (-2750 4825);
PAINT SKYBLUE (-2750 4825);
FORCEPROP 1 LAST TOLERANCE 1%
J 0
(-3050 4775);
DISPLAY 0.617021 (-3050 4775);
PAINT SKYBLUE (-3050 4775);
FORCEPROP 1 LASTPIN (-3075 4775) $PN 2
J 0
(-3113 4787);
DISPLAY 0.617021 (-3113 4787);
PAINT MONO (-3113 4787);
FORCEPROP 1 LASTPIN (-3275 4775) $PN 1
J 0
(-3263 4787);
DISPLAY 0.617021 (-3263 4787);
PAINT MONO (-3263 4787);
FORCEPROP 1 LAST PART_NUMBER G21796-173
J 0
(-3200 4825);
DISPLAY 0.638298 (-3200 4825);
PAINT BLUE (-3200 4825);
FORCEPROP 1 LAST MATERIAL CHIP
J 0
(-3375 4775);
DISPLAY 0.617021 (-3375 4775);
PAINT SKYBLUE (-3375 4775);
FORCEPROP 1 LAST LOCATION R1U9
J 0
(-3375 4825);
DISPLAY 0.617021 (-3375 4825);
PAINT AQUA (-3375 4825);
FORCEPROP 2 LAST ROOM SMBUS
J 0
(-3225 4875);
DISPLAY 1.021277 (-3225 4875);
PAINT ORANGE (-3225 4875);
DISPLAY INVISIBLE (-3225 4875);
FORCEPROP 2 LAST CDS_LOCATION R1U9
J 0
(-3225 4825);
DISPLAY 0.617021 (-3225 4825);
PAINT AQUA (-3225 4825);
DISPLAY INVISIBLE (-3225 4825);
FORCEPROP 2 LAST CDS_LIB mstr_discrete
J 0
(-3175 4775);
PAINT ORANGE (-3175 4775);
DISPLAY INVISIBLE (-3175 4775);
FORCEPROP 1 LAST PATH I232
J 0
(-3225 4925);
DISPLAY 0.978723 (-3225 4925);
PAINT WHITE (-3225 4925);
DISPLAY INVISIBLE (-3225 4925);
FORCEPROP 2 LAST BOM_COST SM_CONTROLLER
J 0
(-3225 4925);
DISPLAY 1.021277 (-3225 4925);
PAINT ORANGE (-3225 4925);
DISPLAY INVISIBLE (-3225 4925);
FORCEPROP 2 LAST $SEC 1
J 0
(-3225 4975);
DISPLAY 0.936170 (-3225 4975);
PAINT MONO (-3225 4975);
DISPLAY INVISIBLE (-3225 4975);
FORCEPROP 2 LAST CDS_SEC 1
J 0
(-3225 4975);
DISPLAY 1.404255 (-3225 4975);
PAINT ORANGE (-3225 4975);
DISPLAY INVISIBLE (-3225 4975);
FORCEADD RES..1
(-3175 4950);
FORCEPROP 1 LAST WATTAGE 1/16W
J 0
(-2750 5000);
DISPLAY 0.638298 (-2750 5000);
PAINT SKYBLUE (-2750 5000);
FORCEPROP 1 LAST LOCATION R1U10
J 0
(-3375 5000);
DISPLAY 0.617021 (-3375 5000);
PAINT AQUA (-3375 5000);
FORCEPROP 1 LAST MATERIAL CHIP
J 0
(-3375 4950);
DISPLAY 0.617021 (-3375 4950);
PAINT SKYBLUE (-3375 4950);
FORCEPROP 1 LASTPIN (-3275 4950) $PN 1
J 0
(-3263 4962);
DISPLAY 0.617021 (-3263 4962);
PAINT MONO (-3263 4962);
FORCEPROP 1 LASTPIN (-3075 4950) $PN 2
J 0
(-3113 4962);
DISPLAY 0.617021 (-3113 4962);
PAINT MONO (-3113 4962);
FORCEPROP 1 LAST TOLERANCE 1%
J 0
(-3050 4950);
DISPLAY 0.617021 (-3050 4950);
PAINT SKYBLUE (-3050 4950);
FORCEPROP 1 LAST VALUE 20.0
J 2
(-2875 4950);
DISPLAY 0.617021 (-2875 4950);
PAINT SKYBLUE (-2875 4950);
FORCEPROP 1 LAST PACK_TYPE 0402
J 0
(-2900 5000);
DISPLAY 0.638298 (-2900 5000);
PAINT SKYBLUE (-2900 5000);
FORCEPROP 1 LAST PART_NUMBER G21796-173
J 0
(-3200 5000);
DISPLAY 0.638298 (-3200 5000);
PAINT BLUE (-3200 5000);
FORCEPROP 2 LAST CDS_LOCATION R1U10
J 0
(-3225 5000);
DISPLAY 0.617021 (-3225 5000);
PAINT AQUA (-3225 5000);
DISPLAY INVISIBLE (-3225 5000);
FORCEPROP 2 LAST BOM_COST SM_CONTROLLER
J 0
(-3225 5100);
DISPLAY 1.021277 (-3225 5100);
PAINT ORANGE (-3225 5100);
DISPLAY INVISIBLE (-3225 5100);
FORCEPROP 1 LAST PATH I233
J 0
(-3225 5100);
DISPLAY 0.978723 (-3225 5100);
PAINT WHITE (-3225 5100);
DISPLAY INVISIBLE (-3225 5100);
FORCEPROP 2 LAST ROOM SMBUS
J 0
(-3225 5050);
DISPLAY 1.021277 (-3225 5050);
PAINT ORANGE (-3225 5050);
DISPLAY INVISIBLE (-3225 5050);
FORCEPROP 2 LAST CDS_LIB mstr_discrete
J 0
(-3175 4950);
PAINT ORANGE (-3175 4950);
DISPLAY INVISIBLE (-3175 4950);
FORCEPROP 2 LAST $SEC 1
J 0
(-3225 5150);
DISPLAY 0.936170 (-3225 5150);
PAINT MONO (-3225 5150);
DISPLAY INVISIBLE (-3225 5150);
FORCEPROP 2 LAST CDS_SEC 1
J 0
(-3225 5150);
DISPLAY 1.404255 (-3225 5150);
PAINT ORANGE (-3225 5150);
DISPLAY INVISIBLE (-3225 5150);
FORCEADD P3V3_STBY..1
(-3500 4325);
FORCEPROP 3 LASTPIN (-3500 4275) SIG_NAME P3V3_STBY\g
J 0
(-3490 4285);
DISPLAY 0.659574 (-3490 4285);
PAINT MONO (-3490 4285);
DISPLAY INVISIBLE (-3490 4285);
FORCEPROP 1 LAST VOLTAGE 3.3V
J 0
(-3545 4282);
DISPLAY 0.340426 (-3545 4282);
PAINT SKYBLUE (-3545 4282);
DISPLAY INVISIBLE (-3545 4282);
FORCEPROP 2 LAST CDS_LIB mstr_symbols
J 0
(-3500 4325);
PAINT ORANGE (-3500 4325);
DISPLAY INVISIBLE (-3500 4325);
FORCEPROP 1 LAST SIZE 1B
J 0
(-3455 4347);
DISPLAY 0.340426 (-3455 4347);
PAINT GREEN (-3455 4347);
DISPLAY INVISIBLE (-3455 4347);
FORCEPROP 1 LAST PATH I234
J 0
(-3455 4327);
DISPLAY 0.340426 (-3455 4327);
PAINT GREEN (-3455 4327);
DISPLAY INVISIBLE (-3455 4327);
FORCEPROP 1 LAST BODY_TYPE PLUMBING
J 0
(-3545 4282);
DISPLAY 0.340426 (-3545 4282);
PAINT GREEN (-3545 4282);
DISPLAY INVISIBLE (-3545 4282);
FORCEPROP 1 LAST HDL_POWER P3V3_STBY
J 0
(-3800 4200);
DISPLAY 0.872340 (-3800 4200);
PAINT ORANGE (-3800 4200);
DISPLAY INVISIBLE (-3800 4200);
FORCEADD RES..2
(-3500 4100);
FORCEPROP 1 LAST PACK_TYPE 0402
J 0
(-3460 3925);
DISPLAY 0.617021 (-3460 3925);
PAINT SKYBLUE (-3460 3925);
FORCEPROP 1 LASTPIN (-3500 4200) $PN 1
J 0
(-3495 4162);
DISPLAY 0.787234 (-3495 4162);
PAINT ORANGE (-3495 4162);
FORCEPROP 1 LASTPIN (-3500 4000) $PN 2
J 0
(-3495 4010);
DISPLAY 0.787234 (-3495 4010);
PAINT ORANGE (-3495 4010);
FORCEPROP 1 LAST TOLERANCE 1%
J 0
(-3455 4125);
DISPLAY 0.617021 (-3455 4125);
PAINT SKYBLUE (-3455 4125);
FORCEPROP 1 LAST MATERIAL CHIP
J 0
(-3460 4025);
DISPLAY 0.617021 (-3460 4025);
PAINT SKYBLUE (-3460 4025);
FORCEPROP 1 LAST PART_NUMBER G21796-001
J 0
(-3460 3975);
DISPLAY 0.617021 (-3460 3975);
PAINT BLUE (-3460 3975);
FORCEPROP 1 LAST WATTAGE 1/16W
J 0
(-3460 4075);
DISPLAY 0.617021 (-3460 4075);
PAINT SKYBLUE (-3460 4075);
FORCEPROP 1 LAST LOCATION R8C15
J 0
(-3455 4225);
DISPLAY 0.617021 (-3455 4225);
PAINT AQUA (-3455 4225);
FORCEPROP 1 LAST VALUE 2.0K
J 0
(-3455 4175);
DISPLAY 0.617021 (-3455 4175);
PAINT SKYBLUE (-3455 4175);
FORCEPROP 2 LAST CDS_LIB mstr_discrete
J 0
(-3500 4100);
PAINT ORANGE (-3500 4100);
DISPLAY INVISIBLE (-3500 4100);
FORCEPROP 2 LAST ROOM SMBUS
J 0
(-3450 4325);
DISPLAY 1.021277 (-3450 4325);
PAINT ORANGE (-3450 4325);
DISPLAY INVISIBLE (-3450 4325);
FORCEPROP 2 LAST BOM_COST SM_CONTROLLER
J 0
(-3450 4425);
DISPLAY 1.021277 (-3450 4425);
PAINT ORANGE (-3450 4425);
DISPLAY INVISIBLE (-3450 4425);
FORCEPROP 2 LAST CDS_LOCATION R8C15
J 0
(-3455 4225);
DISPLAY 0.617021 (-3455 4225);
PAINT AQUA (-3455 4225);
DISPLAY INVISIBLE (-3455 4225);
FORCEPROP 2 LAST SEC_TYPE 0402
J 0
(-3450 4325);
DISPLAY 1.021277 (-3450 4325);
PAINT ORANGE (-3450 4325);
DISPLAY INVISIBLE (-3450 4325);
FORCEPROP 0 LAST SEC 1
J 0
(-3450 4275);
DISPLAY 0.680851 (-3450 4275);
PAINT MONO (-3450 4275);
DISPLAY INVISIBLE (-3450 4275);
FORCEPROP 0 LAST CDS_SEC 1
J 0
(-3450 4275);
PAINT MONO (-3450 4275);
DISPLAY INVISIBLE (-3450 4275);
FORCEPROP 1 LAST PATH I235
J 0
(-3450 4275);
DISPLAY 0.978723 (-3450 4275);
PAINT WHITE (-3450 4275);
DISPLAY INVISIBLE (-3450 4275);
FORCEADD P3V3_STBY..1
(-3900 4375);
FORCEPROP 3 LASTPIN (-3900 4325) SIG_NAME P3V3_STBY\g
J 0
(-3890 4335);
DISPLAY 0.659574 (-3890 4335);
PAINT MONO (-3890 4335);
DISPLAY INVISIBLE (-3890 4335);
FORCEPROP 1 LAST VOLTAGE 3.3V
J 0
(-3945 4332);
DISPLAY 0.340426 (-3945 4332);
PAINT SKYBLUE (-3945 4332);
DISPLAY INVISIBLE (-3945 4332);
FORCEPROP 2 LAST CDS_LIB mstr_symbols
J 0
(-3900 4375);
PAINT ORANGE (-3900 4375);
DISPLAY INVISIBLE (-3900 4375);
FORCEPROP 1 LAST SIZE 1B
J 0
(-3855 4397);
DISPLAY 0.340426 (-3855 4397);
PAINT GREEN (-3855 4397);
DISPLAY INVISIBLE (-3855 4397);
FORCEPROP 1 LAST PATH I236
J 0
(-3855 4377);
DISPLAY 0.340426 (-3855 4377);
PAINT GREEN (-3855 4377);
DISPLAY INVISIBLE (-3855 4377);
FORCEPROP 1 LAST BODY_TYPE PLUMBING
J 0
(-3945 4332);
DISPLAY 0.340426 (-3945 4332);
PAINT GREEN (-3945 4332);
DISPLAY INVISIBLE (-3945 4332);
FORCEPROP 1 LAST HDL_POWER P3V3_STBY
J 0
(-4200 4250);
DISPLAY 0.872340 (-4200 4250);
PAINT ORANGE (-4200 4250);
DISPLAY INVISIBLE (-4200 4250);
FORCEADD RES..2
(-3900 4150);
FORCEPROP 1 LAST MATERIAL CHIP
J 0
(-3860 4075);
DISPLAY 0.617021 (-3860 4075);
PAINT SKYBLUE (-3860 4075);
FORCEPROP 1 LASTPIN (-3900 4050) $PN 2
J 0
(-3895 4060);
DISPLAY 0.787234 (-3895 4060);
PAINT ORANGE (-3895 4060);
FORCEPROP 1 LASTPIN (-3900 4250) $PN 1
J 0
(-3895 4212);
DISPLAY 0.787234 (-3895 4212);
PAINT ORANGE (-3895 4212);
FORCEPROP 1 LAST TOLERANCE 1%
J 0
(-3855 4175);
DISPLAY 0.617021 (-3855 4175);
PAINT SKYBLUE (-3855 4175);
FORCEPROP 1 LAST VALUE 2.0K
J 0
(-3855 4225);
DISPLAY 0.617021 (-3855 4225);
PAINT SKYBLUE (-3855 4225);
FORCEPROP 1 LAST LOCATION R8C16
J 0
(-3855 4275);
DISPLAY 0.617021 (-3855 4275);
PAINT AQUA (-3855 4275);
FORCEPROP 1 LAST PACK_TYPE 0402
J 0
(-3860 3975);
DISPLAY 0.617021 (-3860 3975);
PAINT SKYBLUE (-3860 3975);
FORCEPROP 1 LAST PART_NUMBER G21796-001
J 0
(-3860 4025);
DISPLAY 0.617021 (-3860 4025);
PAINT BLUE (-3860 4025);
FORCEPROP 1 LAST WATTAGE 1/16W
J 0
(-3860 4125);
DISPLAY 0.617021 (-3860 4125);
PAINT SKYBLUE (-3860 4125);
FORCEPROP 2 LAST CDS_LIB mstr_discrete
J 0
(-3900 4150);
PAINT ORANGE (-3900 4150);
DISPLAY INVISIBLE (-3900 4150);
FORCEPROP 2 LAST ROOM SMBUS
J 0
(-3850 4375);
DISPLAY 1.021277 (-3850 4375);
PAINT ORANGE (-3850 4375);
DISPLAY INVISIBLE (-3850 4375);
FORCEPROP 2 LAST CDS_LOCATION R8C16
J 0
(-3855 4275);
DISPLAY 0.617021 (-3855 4275);
PAINT AQUA (-3855 4275);
DISPLAY INVISIBLE (-3855 4275);
FORCEPROP 2 LAST BOM_COST SM_CONTROLLER
J 0
(-3850 4475);
DISPLAY 1.021277 (-3850 4475);
PAINT ORANGE (-3850 4475);
DISPLAY INVISIBLE (-3850 4475);
FORCEPROP 2 LAST SEC_TYPE 0402
J 0
(-3850 4375);
DISPLAY 1.021277 (-3850 4375);
PAINT ORANGE (-3850 4375);
DISPLAY INVISIBLE (-3850 4375);
FORCEPROP 0 LAST SEC 1
J 0
(-3850 4325);
DISPLAY 0.680851 (-3850 4325);
PAINT MONO (-3850 4325);
DISPLAY INVISIBLE (-3850 4325);
FORCEPROP 0 LAST CDS_SEC 1
J 0
(-3850 4325);
PAINT MONO (-3850 4325);
DISPLAY INVISIBLE (-3850 4325);
FORCEPROP 1 LAST PATH I237
J 0
(-3850 4325);
DISPLAY 0.978723 (-3850 4325);
PAINT WHITE (-3850 4325);
DISPLAY INVISIBLE (-3850 4325);
FORCEADD OFFPAGE..2
(2025 4275);
FORCEPROP 2 LAST $XR3 188 
J 0
(2544 4275);
DISPLAY 0.638298 (2544 4275);
PAINT MONO (2544 4275);
FORCEPROP 2 LAST $XR2 186 
J 0
(2424 4275);
DISPLAY 0.638298 (2424 4275);
PAINT MONO (2424 4275);
FORCEPROP 2 LAST $XR1 91 
J 0
(2334 4275);
DISPLAY 0.638298 (2334 4275);
PAINT MONO (2334 4275);
FORCEPROP 2 LAST $XR0 138 
J 0
(2214 4275);
DISPLAY 0.638298 (2214 4275);
PAINT MONO (2214 4275);
FORCEPROP 2 LAST PATH I75
J 0
(2350 4325);
DISPLAY 1.021277 (2350 4325);
PAINT ORANGE (2350 4325);
DISPLAY INVISIBLE (2350 4325);
FORCEPROP 2 LAST CDS_LIB mstr_standard
J 0
(2025 4275);
PAINT ORANGE (2025 4275);
DISPLAY INVISIBLE (2025 4275);
FORCEPROP 1 LAST OFFPAGE TRUE
J 0
(2350 4150);
DISPLAY 0.872340 (2350 4150);
PAINT GREEN (2350 4150);
DISPLAY INVISIBLE (2350 4150);
FORCEPROP 1 LAST COMMENT_BODY TRUE
J 0
(1980 4180);
DISPLAY 0.872340 (1980 4180);
PAINT GREEN (1980 4180);
DISPLAY INVISIBLE (1980 4180);
FORCEADD OFFPAGE..2
(2025 3375);
FORCEPROP 2 LAST $XR3 199 
J 0
(2214 3339);
DISPLAY 0.638298 (2214 3339);
PAINT MONO (2214 3339);
FORCEPROP 2 LAST $XR2 247 
J 0
(2454 3375);
DISPLAY 0.638298 (2454 3375);
PAINT MONO (2454 3375);
FORCEPROP 2 LAST $XR1 181 
J 0
(2334 3375);
DISPLAY 0.638298 (2334 3375);
PAINT MONO (2334 3375);
FORCEPROP 2 LAST $XR0 138 
J 0
(2214 3375);
DISPLAY 0.638298 (2214 3375);
PAINT MONO (2214 3375);
FORCEPROP 2 LAST CDS_LIB mstr_standard
J 0
(2025 3375);
PAINT ORANGE (2025 3375);
DISPLAY INVISIBLE (2025 3375);
FORCEPROP 2 LAST PATH I76
J 0
(2350 3425);
DISPLAY 1.021277 (2350 3425);
PAINT ORANGE (2350 3425);
DISPLAY INVISIBLE (2350 3425);
FORCEPROP 1 LAST OFFPAGE TRUE
J 0
(2350 3250);
DISPLAY 0.872340 (2350 3250);
PAINT GREEN (2350 3250);
DISPLAY INVISIBLE (2350 3250);
FORCEPROP 1 LAST COMMENT_BODY TRUE
J 0
(1980 3280);
DISPLAY 0.872340 (1980 3280);
PAINT GREEN (1980 3280);
DISPLAY INVISIBLE (1980 3280);
FORCEADD OFFPAGE..3
(2025 4450);
FORCEPROP 2 LAST $XR3 188 
J 0
(2239 4414);
DISPLAY 0.638298 (2239 4414);
PAINT MONO (2239 4414);
FORCEPROP 2 LAST $XR2 186 
J 0
(2449 4450);
DISPLAY 0.638298 (2449 4450);
PAINT MONO (2449 4450);
FORCEPROP 2 LAST $XR1 138 
J 0
(2329 4450);
DISPLAY 0.638298 (2329 4450);
PAINT MONO (2329 4450);
FORCEPROP 2 LAST $XR0 91 
J 0
(2239 4450);
DISPLAY 0.638298 (2239 4450);
PAINT MONO (2239 4450);
FORCEPROP 2 LAST PATH I77
J 0
(2375 4500);
DISPLAY 1.021277 (2375 4500);
PAINT ORANGE (2375 4500);
DISPLAY INVISIBLE (2375 4500);
FORCEPROP 2 LAST CDS_LIB mstr_standard
J 0
(2025 4450);
PAINT ORANGE (2025 4450);
DISPLAY INVISIBLE (2025 4450);
FORCEPROP 1 LAST OFFPAGE TRUE
J 0
(2350 4325);
DISPLAY 0.872340 (2350 4325);
PAINT GREEN (2350 4325);
DISPLAY INVISIBLE (2350 4325);
FORCEPROP 1 LAST COMMENT_BODY TRUE
J 0
(1975 4350);
DISPLAY 0.872340 (1975 4350);
PAINT GREEN (1975 4350);
DISPLAY INVISIBLE (1975 4350);
FORCEADD OFFPAGE..3
(2025 3550);
FORCEPROP 2 LAST $XR3 247 
J 0
(2239 3514);
DISPLAY 0.638298 (2239 3514);
PAINT MONO (2239 3514);
FORCEPROP 2 LAST $XR2 199 
J 0
(2479 3550);
DISPLAY 0.638298 (2479 3550);
PAINT MONO (2479 3550);
FORCEPROP 2 LAST $XR1 181 
J 0
(2359 3550);
DISPLAY 0.638298 (2359 3550);
PAINT MONO (2359 3550);
FORCEPROP 2 LAST $XR0 138 
J 0
(2239 3550);
DISPLAY 0.638298 (2239 3550);
PAINT MONO (2239 3550);
FORCEPROP 2 LAST CDS_LIB mstr_standard
J 0
(2025 3550);
PAINT ORANGE (2025 3550);
DISPLAY INVISIBLE (2025 3550);
FORCEPROP 2 LAST PATH I78
J 0
(2375 3600);
DISPLAY 1.021277 (2375 3600);
PAINT ORANGE (2375 3600);
DISPLAY INVISIBLE (2375 3600);
FORCEPROP 1 LAST OFFPAGE TRUE
J 0
(2350 3425);
DISPLAY 0.872340 (2350 3425);
PAINT GREEN (2350 3425);
DISPLAY INVISIBLE (2350 3425);
FORCEPROP 1 LAST COMMENT_BODY TRUE
J 0
(1975 3450);
DISPLAY 0.872340 (1975 3450);
PAINT GREEN (1975 3450);
DISPLAY INVISIBLE (1975 3450);
FORCEADD OFFPAGE..3
(1875 1775);
FORCEPROP 2 LAST $XR11 235 
J 0
(2449 1811);
DISPLAY 0.638298 (2449 1811);
PAINT MONO (2449 1811);
FORCEPROP 2 LAST $XR10 226 
J 0
(2329 1811);
DISPLAY 0.638298 (2329 1811);
PAINT MONO (2329 1811);
FORCEPROP 2 LAST $XR9 223 
J 0
(2209 1811);
DISPLAY 0.638298 (2209 1811);
PAINT MONO (2209 1811);
FORCEPROP 2 LAST $XR8 218 
J 0
(2089 1811);
DISPLAY 0.638298 (2089 1811);
PAINT MONO (2089 1811);
FORCEPROP 2 LAST $XR7 215 
J 0
(2449 1739);
DISPLAY 0.638298 (2449 1739);
PAINT MONO (2449 1739);
FORCEPROP 2 LAST $XR6 213 
J 0
(2329 1739);
DISPLAY 0.638298 (2329 1739);
PAINT MONO (2329 1739);
FORCEPROP 2 LAST $XR5 211 
J 0
(2209 1739);
DISPLAY 0.638298 (2209 1739);
PAINT MONO (2209 1739);
FORCEPROP 2 LAST $XR4 206 
J 0
(2089 1739);
DISPLAY 0.638298 (2089 1739);
PAINT MONO (2089 1739);
FORCEPROP 2 LAST $XR3 201 
J 0
(2449 1775);
DISPLAY 0.638298 (2449 1775);
PAINT MONO (2449 1775);
FORCEPROP 2 LAST $XR2 194 
J 0
(2329 1775);
DISPLAY 0.638298 (2329 1775);
PAINT MONO (2329 1775);
FORCEPROP 2 LAST $XR1 193 
J 0
(2209 1775);
DISPLAY 0.638298 (2209 1775);
PAINT MONO (2209 1775);
FORCEPROP 2 LAST $XR0 138 
J 0
(2089 1775);
DISPLAY 0.638298 (2089 1775);
PAINT MONO (2089 1775);
FORCEPROP 2 LAST PATH I79
J 0
(2225 1825);
DISPLAY 1.021277 (2225 1825);
PAINT ORANGE (2225 1825);
DISPLAY INVISIBLE (2225 1825);
FORCEPROP 2 LAST CDS_LIB mstr_standard
J 0
(1875 1775);
PAINT ORANGE (1875 1775);
DISPLAY INVISIBLE (1875 1775);
FORCEPROP 1 LAST OFFPAGE TRUE
J 0
(2200 1650);
DISPLAY 0.872340 (2200 1650);
PAINT GREEN (2200 1650);
DISPLAY INVISIBLE (2200 1650);
FORCEPROP 1 LAST COMMENT_BODY TRUE
J 0
(1825 1675);
DISPLAY 0.872340 (1825 1675);
PAINT GREEN (1825 1675);
DISPLAY INVISIBLE (1825 1675);
FORCEADD OFFPAGE..2
(1875 1600);
FORCEPROP 2 LAST $XR11 226 
J 0
(2664 1564);
DISPLAY 0.638298 (2664 1564);
PAINT MONO (2664 1564);
FORCEPROP 2 LAST $XR10 223 
J 0
(2544 1564);
DISPLAY 0.638298 (2544 1564);
PAINT MONO (2544 1564);
FORCEPROP 2 LAST $XR9 218 
J 0
(2424 1564);
DISPLAY 0.638298 (2424 1564);
PAINT MONO (2424 1564);
FORCEPROP 2 LAST $XR8 215 
J 0
(2304 1564);
DISPLAY 0.638298 (2304 1564);
PAINT MONO (2304 1564);
FORCEPROP 2 LAST $XR7 206 
J 0
(2184 1564);
DISPLAY 0.638298 (2184 1564);
PAINT MONO (2184 1564);
FORCEPROP 2 LAST $XR6 201 
J 0
(2064 1564);
DISPLAY 0.638298 (2064 1564);
PAINT MONO (2064 1564);
FORCEPROP 2 LAST $XR5 194 
J 0
(2664 1600);
DISPLAY 0.638298 (2664 1600);
PAINT MONO (2664 1600);
FORCEPROP 2 LAST $XR4 193 
J 0
(2544 1600);
DISPLAY 0.638298 (2544 1600);
PAINT MONO (2544 1600);
FORCEPROP 2 LAST $XR3 235 
J 0
(2424 1600);
DISPLAY 0.638298 (2424 1600);
PAINT MONO (2424 1600);
FORCEPROP 2 LAST $XR2 213 
J 0
(2304 1600);
DISPLAY 0.638298 (2304 1600);
PAINT MONO (2304 1600);
FORCEPROP 2 LAST $XR1 211 
J 0
(2184 1600);
DISPLAY 0.638298 (2184 1600);
PAINT MONO (2184 1600);
FORCEPROP 2 LAST $XR0 138 
J 0
(2064 1600);
DISPLAY 0.638298 (2064 1600);
PAINT MONO (2064 1600);
FORCEPROP 2 LAST PATH I83
J 0
(2200 1650);
DISPLAY 1.021277 (2200 1650);
PAINT ORANGE (2200 1650);
DISPLAY INVISIBLE (2200 1650);
FORCEPROP 2 LAST CDS_LIB mstr_standard
J 0
(1875 1600);
PAINT ORANGE (1875 1600);
DISPLAY INVISIBLE (1875 1600);
FORCEPROP 1 LAST OFFPAGE TRUE
J 0
(2200 1475);
DISPLAY 0.872340 (2200 1475);
PAINT GREEN (2200 1475);
DISPLAY INVISIBLE (2200 1475);
FORCEPROP 1 LAST COMMENT_BODY TRUE
J 0
(1830 1505);
DISPLAY 0.872340 (1830 1505);
PAINT GREEN (1830 1505);
DISPLAY INVISIBLE (1830 1505);
FORCEADD CAD_NOTE..1
(-3300 2175);
FORCEPROP 0 LAST L1 PLACE RESISTORS CLOSE TO BMC
J 0
(-3975 2025);
DISPLAY 1.021277 (-3975 2025);
PAINT ORANGE (-3975 2025);
FORCEPROP 2 LAST CDS_LIB mstr_symbols
J 0
(-3300 2175);
PAINT ORANGE (-3300 2175);
DISPLAY INVISIBLE (-3300 2175);
FORCEPROP 1 LAST COMMENT_BODY TRUE
J 0
(-3275 2275);
DISPLAY 0.978723 (-3275 2275);
PAINT ORANGE (-3275 2275);
DISPLAY INVISIBLE (-3275 2275);
FORCEADD CAD_NOTE..1
(-3875 1000);
FORCEPROP 0 LAST L2 FOR QUESTIONS, ASK MAX
J 0
(-4000 825);
DISPLAY 0.808511 (-4000 825);
PAINT ORANGE (-4000 825);
FORCEPROP 0 LAST L1 RUN TRACES THROUGH RESISTOR PADS ON OCP AND SMLINK0 CONNECTIONS
J 0
(-4000 875);
DISPLAY 0.808511 (-4000 875);
PAINT ORANGE (-4000 875);
FORCEPROP 2 LAST CDS_LIB mstr_symbols
J 0
(-3875 1000);
PAINT MONO (-3875 1000);
DISPLAY INVISIBLE (-3875 1000);
FORCEPROP 1 LAST COMMENT_BODY TRUE
J 0
(-3850 1100);
DISPLAY 0.978723 (-3850 1100);
PAINT ORANGE (-3850 1100);
DISPLAY INVISIBLE (-3850 1100);
FORCEADD INTEL_CORP_BPAGE..1
(2650 500);
FORCEPROP 1 LAST CDS_CON_LAST_MODIFIED Fri Jun 16 17:48:59 2017
J 0
(1225 825);
PAINT ORANGE (1225 825);
DISPLAY INVISIBLE (1225 825);
FORCEPROP 1 LAST CUSTOM_TXT_CDS <CURRENT_DESIGN_SHEET> OF <TOTAL_DESIGN_SHEETS>
J 0
(2150 525);
PAINT ORANGE (2150 525);
FORCEPROP 1 LAST CUSTOM_TXT_CDS <CON_LAST_MODIFIED>
J 0
(-1350 600);
PAINT ORANGE (-1350 600);
FORCEPROP 2 LAST CUSTOM_TXT_CDS <XR_PAGE_TITLE>
J 0
(-5240 5750);
DISPLAY 0.638298 (-5240 5750);
PAINT PINK (-5240 5750);
DISPLAY INVISIBLE (-5240 5750);
FORCEPROP 1 LAST SCH_TITLE SMBUS PULLUPS (1 OF 2)
J 0
(-5300 550);
DISPLAY 1.212766 (-5300 550);
PAINT ORANGE (-5300 550);
FORCEPROP 2 LAST CDS_LIB mstr_symbols
J 0
(2650 500);
PAINT MONO (2650 500);
DISPLAY INVISIBLE (2650 500);
FORCEPROP 2 LAST PAGE_BORDER TRUE
J 0
(-5240 5750);
DISPLAY 0.851064 (-5240 5750);
PAINT PINK (-5240 5750);
DISPLAY INVISIBLE (-5240 5750);
FORCEPROP 1 LAST COMMENT_BODY TRUE
J 0
(2662 512);
DISPLAY 0.468085 (2662 512);
PAINT GREEN (2662 512);
DISPLAY INVISIBLE (2662 512);
FORCEPROP 2 LAST CDS_XR_PAGE_TITLE CR-159 : @BASEBOARD_FAB2_LIB.BASEBOARD_FAB2(SCH_1):PAGE159
J 0
(-5240 5750);
DISPLAY 0.638298 (-5240 5750);
PAINT PINK (-5240 5750);
DISPLAY INVISIBLE (-5240 5750);
FORCEADD DNS..2
(-3370 2895);
PAINT RED (-3370 2895);
FORCEPROP 2 LAST CDS_LIB mstr_misc
J 0
(-3370 2895);
PAINT ORANGE (-3370 2895);
DISPLAY INVISIBLE (-3370 2895);
FORCEPROP 1 LAST COMMENT_BODY TRUE
R 1
J 0
(-3295 2670);
DISPLAY 0.872340 (-3295 2670);
PAINT GREEN (-3295 2670);
DISPLAY INVISIBLE (-3295 2670);
FORCEADD DNS..2
(-3720 2895);
PAINT RED (-3720 2895);
FORCEPROP 2 LAST CDS_LIB mstr_misc
J 0
(-3720 2895);
PAINT ORANGE (-3720 2895);
DISPLAY INVISIBLE (-3720 2895);
FORCEPROP 1 LAST COMMENT_BODY TRUE
R 1
J 0
(-3645 2670);
DISPLAY 0.872340 (-3645 2670);
PAINT GREEN (-3645 2670);
DISPLAY INVISIBLE (-3645 2670);
FORCEADD CAD_NOTE..1
(600 1475);
FORCEPROP 0 LAST L1 PLACE RESISTORS CLOSE TO BMC
J 0
(-75 1325);
DISPLAY 1.021277 (-75 1325);
PAINT ORANGE (-75 1325);
FORCEPROP 2 LAST CDS_LIB mstr_symbols
J 0
(600 1475);
PAINT ORANGE (600 1475);
DISPLAY INVISIBLE (600 1475);
FORCEPROP 1 LAST COMMENT_BODY TRUE
J 0
(625 1575);
DISPLAY 0.978723 (625 1575);
PAINT ORANGE (625 1575);
DISPLAY INVISIBLE (625 1575);
WIRE 16 -1 (-3375 3150)(-3375 3000);
WIRE 16 -1 (-3725 3150)(-3725 3000);
WIRE 16 -1 (550 5075)(550 4925);
WIRE 16 -1 (200 5075)(200 4925);
WIRE 16 -1 (-3500 4200)(-3500 4275);
WIRE 16 -1 (-3900 4250)(-3900 4325);
WIRE 16 -1 (-3075 4775)(-2050 4775);
FORCEPROP 0 LAST SIG_NAME SMB_SMLINK0_STBY_LVC3_SCL
J 2
(-2025 4785);
DISPLAY 0.617021 (-2025 4785);
PAINT ORANGE (-2025 4785);
WIRE 16 2175 (-4025 5350)(-4025 1925);
WIRE 16 2175 (-2675 5350)(-4025 5350);
WIRE 16 2175 (-4025 1925)(-2675 1925);
WIRE 16 2175 (-2675 1925)(-2675 5350);
WIRE 16 -1 (-4575 1325)(-3725 1325);
FORCEPROP 2 LAST SIG_NAME SMB_SMLINK0_STBY_LVC3_SCL
J 0
(-4535 1335);
DISPLAY 0.617021 (-4535 1335);
PAINT ORANGE (-4535 1335);
WIRE 16 -1 (-4575 1450)(-3725 1450);
FORCEPROP 2 LAST SIG_NAME SMB_SMLINK0_STBY_LVC3_SDA
J 0
(-4535 1460);
DISPLAY 0.617021 (-4535 1460);
PAINT ORANGE (-4535 1460);
WIRE 16 -1 (600 1775)(-525 1775);
FORCEPROP 2 LAST SIG_NAME SMB_VR_STBY_LVC3_SDA_R
J 0
(-535 1785);
DISPLAY 0.617021 (-535 1785);
PAINT ORANGE (-535 1785);
WIRE 16 -1 (-4575 1575)(-3725 1575);
FORCEPROP 2 LAST SIG_NAME SMB_OCP_LAN_STBY_LVC3_SDA
J 0
(-4535 1585);
DISPLAY 0.617021 (-4535 1585);
PAINT ORANGE (-4535 1585);
WIRE 16 -1 (-3725 2525)(-4350 2525);
FORCEPROP 2 LAST SIG_NAME SMB_OCP_LAN_STBY_LVC3_SDA_R
J 0
(-4360 2535);
DISPLAY 0.617021 (-4360 2535);
PAINT ORANGE (-4360 2535);
WIRE 16 -1 (-3725 2800)(-3725 2525);
WIRE 16 -1 (-2975 2525)(-3725 2525);
WIRE 16 -1 (-3375 2350)(-4350 2350);
FORCEPROP 2 LAST SIG_NAME SMB_OCP_LAN_STBY_LVC3_SCL_R
J 0
(-4335 2360);
DISPLAY 0.617021 (-4335 2360);
PAINT ORANGE (-4335 2360);
WIRE 16 -1 (-3375 2800)(-3375 2350);
WIRE 16 -1 (-2975 2350)(-3375 2350);
WIRE 16 -1 (600 3550)(-550 3550);
FORCEPROP 2 LAST SIG_NAME SMB_BMC_PMBUS_STBY_LVC3_SDA_R
J 0
(-560 3560);
DISPLAY 0.617021 (-560 3560);
PAINT ORANGE (-560 3560);
WIRE 16 -1 (200 4450)(-600 4450);
FORCEPROP 2 LAST SIG_NAME SMB_OCP_FRU_STBY_LVC3_SDA_R
J 0
(-610 4460);
DISPLAY 0.617021 (-610 4460);
PAINT ORANGE (-610 4460);
WIRE 16 -1 (200 4725)(200 4450);
WIRE 16 -1 (700 4450)(200 4450);
WIRE 16 -1 (800 3375)(1975 3375);
FORCEPROP 0 LAST SIG_NAME SMB_BMC_PMBUS_STBY_LVC3_SCL
J 2
(1925 3385);
DISPLAY 0.617021 (1925 3385);
PAINT ORANGE (1925 3385);
WIRE 16 -1 (800 3550)(1975 3550);
FORCEPROP 0 LAST SIG_NAME SMB_BMC_PMBUS_STBY_LVC3_SDA
J 2
(1925 3560);
DISPLAY 0.617021 (1925 3560);
PAINT ORANGE (1925 3560);
WIRE 16 -1 (550 4275)(-600 4275);
FORCEPROP 2 LAST SIG_NAME SMB_OCP_FRU_STBY_LVC3_SCL_R
J 0
(-585 4285);
DISPLAY 0.617021 (-585 4285);
PAINT ORANGE (-585 4285);
WIRE 16 -1 (700 4275)(550 4275);
WIRE 16 -1 (550 4725)(550 4275);
WIRE 16 -1 (600 3375)(-575 3375);
FORCEPROP 2 LAST SIG_NAME SMB_BMC_PMBUS_STBY_LVC3_SCL_R
J 0
(-560 3385);
DISPLAY 0.617021 (-560 3385);
PAINT ORANGE (-560 3385);
WIRE 16 -1 (-3075 3775)(-2050 3775);
FORCEPROP 0 LAST SIG_NAME SMB_HOST_STBY_LVC3_SDA
J 2
(-2025 3785);
DISPLAY 0.617021 (-2025 3785);
PAINT ORANGE (-2025 3785);
WIRE 16 -1 (-3075 3600)(-2050 3600);
FORCEPROP 0 LAST SIG_NAME SMB_HOST_STBY_LVC3_SCL
J 2
(-2025 3610);
DISPLAY 0.617021 (-2025 3610);
PAINT ORANGE (-2025 3610);
WIRE 16 -1 (900 4450)(1975 4450);
FORCEPROP 0 LAST SIG_NAME SMB_OCP_FRU_STBY_LVC3_SDA
J 2
(1875 4460);
DISPLAY 0.617021 (1875 4460);
PAINT ORANGE (1875 4460);
WIRE 16 -1 (900 4275)(1975 4275);
FORCEPROP 0 LAST SIG_NAME SMB_OCP_FRU_STBY_LVC3_SCL
J 2
(1875 4285);
DISPLAY 0.617021 (1875 4285);
PAINT ORANGE (1875 4285);
WIRE 16 -1 (800 1775)(1825 1775);
FORCEPROP 0 LAST SIG_NAME SMB_VR_STBY_LVC3_SDA
J 2
(1850 1785);
DISPLAY 0.617021 (1850 1785);
PAINT ORANGE (1850 1785);
WIRE 16 2175 (-225 5250)(-225 1250);
WIRE 16 2175 (1175 5250)(-225 5250);
WIRE 16 2175 (-225 1250)(1175 1250);
WIRE 16 2175 (1175 1250)(1175 5250);
WIRE 16 -1 (-1800 2350)(-2775 2350);
FORCEPROP 0 LAST SIG_NAME SMB_OCP_LAN_STBY_LVC3_SCL
J 2
(-1775 2360);
DISPLAY 0.617021 (-1775 2360);
PAINT ORANGE (-1775 2360);
WIRE 16 -1 (-4575 1200)(-3725 1200);
FORCEPROP 2 LAST SIG_NAME SMB_OCP_LAN_STBY_LVC3_SCL
J 0
(-4535 1210);
DISPLAY 0.617021 (-4535 1210);
PAINT ORANGE (-4535 1210);
WIRE 16 3135 (-3950 1125)(-4100 1125);
WIRE 16 3135 (-4100 1125)(-4100 750);
WIRE 16 3135 (-3950 1675)(-3950 1125);
WIRE 16 3135 (-3175 1675)(-3950 1675);
WIRE 16 3135 (-4100 750)(-2300 750);
WIRE 16 3135 (-2300 750)(-2300 1075);
WIRE 16 3135 (-3175 1075)(-3175 1675);
WIRE 16 3135 (-3175 1075)(-2300 1075);
WIRE 16 -1 (-3100 1575)(-3525 1575);
WIRE 16 -1 (-3525 1450)(-3100 1450);
WIRE 16 -1 (-3100 1450)(-3100 1575);
WIRE 16 -1 (-3100 1450)(-2125 1450);
FORCEPROP 2 LAST SIG_NAME SMB_SPRINGVILLE_STBY_LVC3_SDA
J 0
(-3085 1460);
DISPLAY 0.617021 (-3085 1460);
PAINT ORANGE (-3085 1460);
WIRE 16 -1 (-3100 1200)(-3525 1200);
WIRE 16 -1 (-3525 1325)(-3100 1325);
WIRE 16 -1 (-3100 1325)(-3100 1200);
WIRE 16 -1 (-3100 1325)(-2125 1325);
FORCEPROP 2 LAST SIG_NAME SMB_SPRINGVILLE_STBY_LVC3_SCL
J 0
(-3085 1335);
DISPLAY 0.617021 (-3085 1335);
PAINT ORANGE (-3085 1335);
WIRE 16 -1 (800 1600)(1825 1600);
FORCEPROP 0 LAST SIG_NAME SMB_VR_STBY_LVC3_SCL
J 2
(1850 1610);
DISPLAY 0.617021 (1850 1610);
PAINT ORANGE (1850 1610);
WIRE 16 -1 (600 1600)(-550 1600);
FORCEPROP 2 LAST SIG_NAME SMB_VR_STBY_LVC3_SCL_R
J 0
(-535 1610);
DISPLAY 0.617021 (-535 1610);
PAINT ORANGE (-535 1610);
WIRE 16 -1 (-1800 2525)(-2775 2525);
FORCEPROP 0 LAST SIG_NAME SMB_OCP_LAN_STBY_LVC3_SDA
J 2
(-1775 2535);
DISPLAY 0.617021 (-1775 2535);
PAINT ORANGE (-1775 2535);
WIRE 16 -1 (-3075 4950)(-2050 4950);
FORCEPROP 0 LAST SIG_NAME SMB_SMLINK0_STBY_LVC3_SDA
J 2
(-2025 4960);
DISPLAY 0.617021 (-2025 4960);
PAINT ORANGE (-2025 4960);
WIRE 16 -1 (-3900 4050)(-3900 3900);
WIRE 16 -1 (-3900 3900)(-3800 3900);
WIRE 16 -1 (-3800 3775)(-4400 3775);
FORCEPROP 2 LAST SIG_NAME SMB_HOST_STBY_LVC3_SDA_R
J 0
(-4410 3785);
DISPLAY 0.617021 (-4410 3785);
PAINT ORANGE (-4410 3785);
WIRE 16 -1 (-3800 3900)(-3800 3775);
WIRE 16 -1 (-3275 3775)(-3800 3775);
WIRE 16 -1 (-3500 3600)(-4400 3600);
FORCEPROP 2 LAST SIG_NAME SMB_HOST_STBY_LVC3_SCL_R
J 0
(-4385 3610);
DISPLAY 0.617021 (-4385 3610);
PAINT ORANGE (-4385 3610);
WIRE 16 -1 (-3500 4000)(-3500 3600);
WIRE 16 -1 (-3275 3600)(-3500 3600);
WIRE 3 682 (-3975 3950)(-3275 3950);
WIRE 3 682 (-3975 4450)(-3975 3950);
WIRE 3 682 (-3275 3950)(-3275 4450);
WIRE 3 682 (-3275 4450)(-3975 4450);
WIRE 16 -1 (-3275 4775)(-4400 4775);
FORCEPROP 2 LAST SIG_NAME SMB_SMLINK0_STBY_LVC3_SCL_R
J 0
(-4385 4785);
DISPLAY 0.617021 (-4385 4785);
PAINT ORANGE (-4385 4785);
WIRE 16 -1 (-3275 4950)(-4400 4950);
FORCEPROP 2 LAST SIG_NAME SMB_SMLINK0_STBY_LVC3_SDA_R
J 0
(-4410 4960);
DISPLAY 0.617021 (-4410 4960);
PAINT ORANGE (-4410 4960);
DOT 1 (-3100 1325);
DOT 1 (-3725 2525);
DOT 1 (-3100 1450);
DOT 1 (-3375 2350);
DOT 1 (550 4275);
DOT 1 (200 4450);
DOT 1 (-3500 3600);
DOT 1 (-3800 3775);
FORCENOTE
TP FAB1 CHANGE CONNCETION 0314
(-3975 4500) 0;
DISPLAY LEFT (-3975 4500);
DISPLAY 1.021277 (-3975 4500);
PAINT RED (-3975 4500);
FORCENOTE
ROOM=SMBUS
(-5280 675) 0;
DISPLAY LEFT (-5280 675);
DISPLAY 0.617021 (-5280 675);
PAINT PURPLE (-5280 675);
QUIT
